G04 ================== begin FILE IDENTIFICATION RECORD ==================*
G04 Layout Name:  x887571-005_osp.brd*
G04 Film Name:    lyr7*
G04 File Format:  Gerber RS274X*
G04 File Origin:  Cadence Allegro 16.3-S036*
G04 Origin Date:  Thu Jul 03 00:06:57 2014*
G04 *
G04 Layer:  VIA CLASS/LYR7*
G04 Layer:  PIN/LYR7*
G04 Layer:  ETCH/LYR7*
G04 Layer:  DRAWING FORMAT/COMMON TEXT*
G04 Layer:  BOARD GEOMETRY/LAYER 7 TEXT*
G04 *
G04 Offset:    (0.0000 0.0000)*
G04 Mirror:    No*
G04 Mode:      Positive*
G04 Rotation:  0*
G04 FullContactRelief:  No*
G04 UndefLineWidth:     4.0000*
G04 ================== end FILE IDENTIFICATION RECORD ====================*
%FSLAX25Y25*MOIN*%
%IR0*IPPOS*OFA0.00000B0.00000*MIA0B0*SFA1.00000B1.00000*%
%ADD12C,.022*%
%ADD15C,.05*%
%ADD14C,.032*%
%ADD17C,.061*%
%ADD20C,.044*%
%ADD11C,.026*%
%ADD21C,.027*%
%ADD13C,.054*%
%ADD18C,.058*%
%ADD19C,.079*%
%ADD16C,.22*%
%ADD10C,.178*%
%ADD22C,.01*%
%ADD23C,.012*%
%ADD24C,.013*%
%ADD25C,.015*%
%ADD26C,.004*%
%ADD27C,.005*%
%ADD28C,.006*%
%ADD29C,.007*%
%ADD30C,.008*%
%ADD40C,.032*%
%ADD41C,.051*%
%ADD42C,.046*%
%ADD38C,.064*%
%ADD37C,.073*%
%ADD33C,.080001*%
%ADD39C,.074*%
%ADD31C,.091001*%
%ADD44C,.098*%
%ADD43C,.099*%
%ADD36C,.092914*%
%ADD35C,.092914*%
%ADD34C,.154001*%
%ADD32C,.186001*%
G75*
%LPD*%
G75*
G36*
G01X-1440241Y-14409D02*
Y9213D01*
G02X-1432598Y16855I7643J0D01*
G01X5433D01*
G02X15044Y7244I0J-9611D01*
G01Y-135827D01*
G03X19213Y-139995I4169J0D01*
G01X19611D01*
Y-175039D01*
G02X10000Y-184650I-9611J0D01*
G01X-335335D01*
G03X-339503Y-188819I0J-4169D01*
G01Y-194650D01*
X-406560D01*
Y-188819D01*
G03X-410728Y-184650I-4169J0D01*
G01X-868784D01*
Y-183850D01*
X-904784D01*
Y-184634D01*
X-905000Y-184850D01*
X-1206847D01*
X-1206935Y-184938D01*
X-1206981Y-184957D01*
G03X-1209582Y-188819I1568J-3862D01*
G01Y-194650D01*
X-1276639D01*
Y-188819D01*
G03X-1280807Y-184650I-4169J0D01*
G01X-1657323D01*
G02X-1661028Y-180945I0J3706D01*
G01Y16175D01*
X-1660114Y17090D01*
X-1625201D01*
X-1624287Y16175D01*
Y-18937D01*
G03X-1617131I3578J0D01*
G01Y16175D01*
X-1616226Y17080D01*
X-1461294D01*
X-1460389Y16175D01*
Y-14409D01*
G03X-1452283Y-22515I8106J0D01*
G01X-1448346D01*
G03X-1440241Y-14409I0J8106D01*
G37*
%LPC*%
G75*
G36*
G01X-91156Y-44741D02*
G02X-83889Y-30498I1195J8365D01*
G02X-84008Y-42373I-6071J-5877D01*
G02X-88932Y-44763I-5953J5997D01*
G03X-89046Y-45725I65J-496D01*
G01X-87619Y-46273D01*
X-86454Y-48771D01*
X-86773Y-49787D01*
X-90342Y-51451D01*
X-91325Y-51043D01*
X-92490Y-48545D01*
X-91600Y-45958D01*
X-91020Y-45688D01*
G03X-91156Y-44741I-211J453D01*
G37*
G36*
G01X-134463D02*
G02X-127197Y-30498I1195J8365D01*
G02X-127315Y-42373I-6071J-5877D01*
G02X-132239Y-44763I-5953J5997D01*
G03X-132353Y-45725I65J-496D01*
G01X-130926Y-46273D01*
X-129761Y-48771D01*
X-130080Y-49787D01*
X-133649Y-51451D01*
X-134632Y-51043D01*
X-135797Y-48545D01*
X-134907Y-45958D01*
X-134327Y-45688D01*
G03X-134463Y-44741I-211J453D01*
G37*
G36*
G01X-961235D02*
G02X-953921Y-30548I1195J8365D01*
G02X-954078Y-42365I-6119J-5828D01*
G02X-959010Y-44763I-5961J5989D01*
G03X-959125Y-45725I65J-496D01*
G01X-957697Y-46273D01*
X-956533Y-48771D01*
X-956852Y-49787D01*
X-960420Y-51451D01*
X-961404Y-51043D01*
X-962569Y-48545D01*
X-961679Y-45958D01*
X-961099Y-45688D01*
G03X-961235Y-44741I-211J453D01*
G37*
G36*
G01X-1004542D02*
G02X-997228Y-30548I1195J8365D01*
G02X-997385Y-42365I-6119J-5828D01*
G02X-1002317Y-44763I-5961J5989D01*
G03X-1002432Y-45725I65J-496D01*
G01X-1001004Y-46273D01*
X-999840Y-48771D01*
X-1000159Y-49787D01*
X-1003727Y-51451D01*
X-1004711Y-51043D01*
X-1005876Y-48545D01*
X-1004986Y-45958D01*
X-1004406Y-45688D01*
G03X-1004542Y-44741I-211J453D01*
G37*
G36*
G01X-21024Y-117826D02*
Y-129370D01*
G02X-44409I-11693J0D01*
G01Y-117826D01*
G02X-21024I11693J12078D01*
G37*
G36*
G01X-86773Y-64748D02*
X-90342Y-66412D01*
X-91325Y-66003D01*
X-92490Y-63505D01*
X-91600Y-60919D01*
X-90172Y-60253D01*
X-87619Y-61234D01*
X-86454Y-63732D01*
X-86773Y-64748D01*
G37*
G36*
G01X-90207Y-52047D02*
X-86678Y-50303D01*
X-85685Y-50689D01*
X-84464Y-53160D01*
X-85296Y-55766D01*
X-86708Y-56464D01*
X-89283Y-55541D01*
X-90504Y-53070D01*
X-90207Y-52047D01*
G37*
G36*
G01X-86773Y-79708D02*
X-90342Y-81372D01*
X-91325Y-80964D01*
X-92490Y-78466D01*
X-91600Y-75879D01*
X-90172Y-75214D01*
X-87619Y-76194D01*
X-86454Y-78692D01*
X-86773Y-79708D01*
G37*
G36*
G01X-90207Y-81968D02*
X-86678Y-80224D01*
X-85685Y-80610D01*
X-84464Y-83081D01*
X-85296Y-85687D01*
X-86708Y-86385D01*
X-89283Y-85462D01*
X-90504Y-82991D01*
X-90207Y-81968D01*
G37*
G36*
G01Y-67007D02*
X-86678Y-65263D01*
X-85685Y-65650D01*
X-84464Y-68121D01*
X-85296Y-70727D01*
X-86708Y-71424D01*
X-89283Y-70501D01*
X-90504Y-68030D01*
X-90207Y-67007D01*
G37*
G36*
G01X-86773Y-94669D02*
X-90342Y-96333D01*
X-91325Y-95924D01*
X-92490Y-93427D01*
X-91600Y-90840D01*
X-90172Y-90174D01*
X-87619Y-91155D01*
X-86454Y-93653D01*
X-86773Y-94669D01*
G37*
G36*
G01X-90207Y-96928D02*
X-86678Y-95185D01*
X-85685Y-95571D01*
X-84464Y-98042D01*
X-85296Y-100648D01*
X-86708Y-101346D01*
X-89283Y-100423D01*
X-90504Y-97952D01*
X-90207Y-96928D01*
G37*
G36*
G01X-95632Y-49787D02*
X-99200Y-51451D01*
X-100184Y-51043D01*
X-101348Y-48545D01*
X-100458Y-45958D01*
X-99031Y-45293D01*
X-96477Y-46273D01*
X-95312Y-48771D01*
X-95632Y-49787D01*
G37*
G36*
G01X-99066Y-52047D02*
X-95536Y-50303D01*
X-94543Y-50689D01*
X-93323Y-53160D01*
X-94154Y-55766D01*
X-95566Y-56464D01*
X-98142Y-55541D01*
X-99362Y-53070D01*
X-99066Y-52047D01*
G37*
G36*
G01X-95632Y-64748D02*
X-99200Y-66412D01*
X-100184Y-66003D01*
X-101348Y-63505D01*
X-100458Y-60919D01*
X-99031Y-60253D01*
X-96477Y-61234D01*
X-95312Y-63732D01*
X-95632Y-64748D01*
G37*
G36*
G01X-99066Y-67007D02*
X-95536Y-65263D01*
X-94543Y-65650D01*
X-93323Y-68121D01*
X-94154Y-70727D01*
X-95566Y-71424D01*
X-98142Y-70501D01*
X-99362Y-68030D01*
X-99066Y-67007D01*
G37*
G36*
G01Y-81968D02*
X-95536Y-80224D01*
X-94543Y-80610D01*
X-93323Y-83081D01*
X-94154Y-85687D01*
X-95566Y-86385D01*
X-98142Y-85462D01*
X-99362Y-82991D01*
X-99066Y-81968D01*
G37*
G36*
G01X-95632Y-79708D02*
X-99200Y-81372D01*
X-100184Y-80964D01*
X-101348Y-78466D01*
X-100458Y-75879D01*
X-99031Y-75214D01*
X-96477Y-76194D01*
X-95312Y-78692D01*
X-95632Y-79708D01*
G37*
G36*
G01X-99066Y-96928D02*
X-95536Y-95185D01*
X-94543Y-95571D01*
X-93323Y-98042D01*
X-94154Y-100648D01*
X-95566Y-101346D01*
X-98142Y-100423D01*
X-99362Y-97952D01*
X-99066Y-96928D01*
G37*
G36*
G01X-95632Y-94669D02*
X-99200Y-96333D01*
X-100184Y-95924D01*
X-101348Y-93427D01*
X-100458Y-90840D01*
X-99031Y-90174D01*
X-96477Y-91155D01*
X-95312Y-93653D01*
X-95632Y-94669D01*
G37*
G36*
G01X-133515Y-52047D02*
X-129985Y-50303D01*
X-128992Y-50689D01*
X-127771Y-53160D01*
X-128603Y-55766D01*
X-130015Y-56464D01*
X-132590Y-55541D01*
X-133811Y-53070D01*
X-133515Y-52047D01*
G37*
G36*
G01X-130080Y-64748D02*
X-133649Y-66412D01*
X-134632Y-66003D01*
X-135797Y-63505D01*
X-134907Y-60919D01*
X-133479Y-60253D01*
X-130926Y-61234D01*
X-129761Y-63732D01*
X-130080Y-64748D01*
G37*
G36*
G01X-142373Y-52047D02*
X-138843Y-50303D01*
X-137850Y-50689D01*
X-136630Y-53160D01*
X-137461Y-55766D01*
X-138874Y-56464D01*
X-141449Y-55541D01*
X-142669Y-53070D01*
X-142373Y-52047D01*
G37*
G36*
G01X-133515Y-67007D02*
X-129985Y-65263D01*
X-128992Y-65650D01*
X-127771Y-68121D01*
X-128603Y-70727D01*
X-130015Y-71424D01*
X-132590Y-70501D01*
X-133811Y-68030D01*
X-133515Y-67007D01*
G37*
G36*
G01Y-81968D02*
X-129985Y-80224D01*
X-128992Y-80610D01*
X-127771Y-83081D01*
X-128603Y-85687D01*
X-130015Y-86385D01*
X-132590Y-85462D01*
X-133811Y-82991D01*
X-133515Y-81968D01*
G37*
G36*
G01X-130080Y-79708D02*
X-133649Y-81372D01*
X-134632Y-80964D01*
X-135797Y-78466D01*
X-134907Y-75879D01*
X-133479Y-75214D01*
X-130926Y-76194D01*
X-129761Y-78692D01*
X-130080Y-79708D01*
G37*
G36*
G01X-142373Y-81968D02*
X-138843Y-80224D01*
X-137850Y-80610D01*
X-136630Y-83081D01*
X-137461Y-85687D01*
X-138874Y-86385D01*
X-141449Y-85462D01*
X-142669Y-82991D01*
X-142373Y-81968D01*
G37*
G36*
G01Y-67007D02*
X-138843Y-65263D01*
X-137850Y-65650D01*
X-136630Y-68121D01*
X-137461Y-70727D01*
X-138874Y-71424D01*
X-141449Y-70501D01*
X-142669Y-68030D01*
X-142373Y-67007D01*
G37*
G36*
G01X-133515Y-96928D02*
X-129985Y-95185D01*
X-128992Y-95571D01*
X-127771Y-98042D01*
X-128603Y-100648D01*
X-130015Y-101346D01*
X-132590Y-100423D01*
X-133811Y-97952D01*
X-133515Y-96928D01*
G37*
G36*
G01X-130080Y-94669D02*
X-133649Y-96333D01*
X-134632Y-95924D01*
X-135797Y-93427D01*
X-134907Y-90840D01*
X-133479Y-90174D01*
X-130926Y-91155D01*
X-129761Y-93653D01*
X-130080Y-94669D01*
G37*
G36*
G01X-142373Y-96928D02*
X-138843Y-95185D01*
X-137850Y-95571D01*
X-136630Y-98042D01*
X-137461Y-100648D01*
X-138874Y-101346D01*
X-141449Y-100423D01*
X-142669Y-97952D01*
X-142373Y-96928D01*
G37*
G36*
G01X-138939Y-49787D02*
X-142507Y-51451D01*
X-143491Y-51043D01*
X-144655Y-48545D01*
X-143765Y-45958D01*
X-142338Y-45293D01*
X-139784Y-46273D01*
X-138619Y-48771D01*
X-138939Y-49787D01*
G37*
G36*
G01Y-64748D02*
X-142507Y-66412D01*
X-143491Y-66003D01*
X-144655Y-63505D01*
X-143765Y-60919D01*
X-142338Y-60253D01*
X-139784Y-61234D01*
X-138619Y-63732D01*
X-138939Y-64748D01*
G37*
G36*
G01Y-79708D02*
X-142507Y-81372D01*
X-143491Y-80964D01*
X-144655Y-78466D01*
X-143765Y-75879D01*
X-142338Y-75214D01*
X-139784Y-76194D01*
X-138619Y-78692D01*
X-138939Y-79708D01*
G37*
G36*
G01Y-94669D02*
X-142507Y-96333D01*
X-143491Y-95924D01*
X-144655Y-93427D01*
X-143765Y-90840D01*
X-142338Y-90174D01*
X-139784Y-91155D01*
X-138619Y-93653D01*
X-138939Y-94669D01*
G37*
G36*
G01X-229171Y-137850D02*
Y-146850D01*
X-230171Y-147850D01*
X-235571D01*
X-236571Y-146850D01*
Y-137850D01*
X-235571Y-136850D01*
X-230171D01*
X-229171Y-137850D01*
G37*
G36*
G01X-248069D02*
Y-146850D01*
X-249069Y-147850D01*
X-254469D01*
X-255469Y-146850D01*
Y-137850D01*
X-254469Y-136850D01*
X-249069D01*
X-248069Y-137850D01*
G37*
G36*
G01X-293268Y-80818D02*
Y-92362D01*
G02X-316654I-11693J0D01*
G01Y-80818D01*
G02X-293268I11693J12078D01*
G37*
G36*
G01X-549173Y-104441D02*
Y-115984D01*
G02X-572559I-11693J0D01*
G01Y-104441D01*
G02X-549173I11693J12078D01*
G37*
G36*
G01X-960286Y-52047D02*
X-956756Y-50303D01*
X-955764Y-50689D01*
X-954543Y-53160D01*
X-955375Y-55766D01*
X-956787Y-56464D01*
X-959362Y-55541D01*
X-960583Y-53070D01*
X-960286Y-52047D01*
G37*
G36*
G01X-956852Y-64748D02*
X-960420Y-66412D01*
X-961404Y-66003D01*
X-962569Y-63505D01*
X-961679Y-60919D01*
X-960251Y-60253D01*
X-957697Y-61234D01*
X-956533Y-63732D01*
X-956852Y-64748D01*
G37*
G36*
G01X-960286Y-67007D02*
X-956756Y-65263D01*
X-955764Y-65650D01*
X-954543Y-68121D01*
X-955375Y-70727D01*
X-956787Y-71424D01*
X-959362Y-70501D01*
X-960583Y-68030D01*
X-960286Y-67007D01*
G37*
G36*
G01Y-81968D02*
X-956756Y-80224D01*
X-955764Y-80610D01*
X-954543Y-83081D01*
X-955375Y-85687D01*
X-956787Y-86385D01*
X-959362Y-85462D01*
X-960583Y-82991D01*
X-960286Y-81968D01*
G37*
G36*
G01X-956852Y-79708D02*
X-960420Y-81372D01*
X-961404Y-80964D01*
X-962569Y-78466D01*
X-961679Y-75879D01*
X-960251Y-75214D01*
X-957697Y-76194D01*
X-956533Y-78692D01*
X-956852Y-79708D01*
G37*
G36*
G01X-960286Y-96928D02*
X-956756Y-95185D01*
X-955764Y-95571D01*
X-954543Y-98042D01*
X-955375Y-100648D01*
X-956787Y-101346D01*
X-959362Y-100423D01*
X-960583Y-97952D01*
X-960286Y-96928D01*
G37*
G36*
G01X-956852Y-94669D02*
X-960420Y-96333D01*
X-961404Y-95924D01*
X-962569Y-93427D01*
X-961679Y-90840D01*
X-960251Y-90174D01*
X-957697Y-91155D01*
X-956533Y-93653D01*
X-956852Y-94669D01*
G37*
G36*
G01X-965710Y-49787D02*
X-969279Y-51451D01*
X-970262Y-51043D01*
X-971427Y-48545D01*
X-970537Y-45958D01*
X-969109Y-45293D01*
X-966556Y-46273D01*
X-965391Y-48771D01*
X-965710Y-49787D01*
G37*
G36*
G01Y-64748D02*
X-969279Y-66412D01*
X-970262Y-66003D01*
X-971427Y-63505D01*
X-970537Y-60919D01*
X-969109Y-60253D01*
X-966556Y-61234D01*
X-965391Y-63732D01*
X-965710Y-64748D01*
G37*
G36*
G01X-969144Y-52047D02*
X-965615Y-50303D01*
X-964622Y-50689D01*
X-963401Y-53160D01*
X-964233Y-55766D01*
X-965645Y-56464D01*
X-968220Y-55541D01*
X-969441Y-53070D01*
X-969144Y-52047D01*
G37*
G36*
G01X-965710Y-79708D02*
X-969279Y-81372D01*
X-970262Y-80964D01*
X-971427Y-78466D01*
X-970537Y-75879D01*
X-969109Y-75214D01*
X-966556Y-76194D01*
X-965391Y-78692D01*
X-965710Y-79708D01*
G37*
G36*
G01X-969144Y-81968D02*
X-965615Y-80224D01*
X-964622Y-80610D01*
X-963401Y-83081D01*
X-964233Y-85687D01*
X-965645Y-86385D01*
X-968220Y-85462D01*
X-969441Y-82991D01*
X-969144Y-81968D01*
G37*
G36*
G01Y-67007D02*
X-965615Y-65263D01*
X-964622Y-65650D01*
X-963401Y-68121D01*
X-964233Y-70727D01*
X-965645Y-71424D01*
X-968220Y-70501D01*
X-969441Y-68030D01*
X-969144Y-67007D01*
G37*
G36*
G01X-965710Y-94669D02*
X-969279Y-96333D01*
X-970262Y-95924D01*
X-971427Y-93427D01*
X-970537Y-90840D01*
X-969109Y-90174D01*
X-966556Y-91155D01*
X-965391Y-93653D01*
X-965710Y-94669D01*
G37*
G36*
G01X-969144Y-96928D02*
X-965615Y-95185D01*
X-964622Y-95571D01*
X-963401Y-98042D01*
X-964233Y-100648D01*
X-965645Y-101346D01*
X-968220Y-100423D01*
X-969441Y-97952D01*
X-969144Y-96928D01*
G37*
G36*
G01X-1000159Y-64748D02*
X-1003727Y-66412D01*
X-1004711Y-66003D01*
X-1005876Y-63505D01*
X-1004986Y-60919D01*
X-1003558Y-60253D01*
X-1001004Y-61234D01*
X-999840Y-63732D01*
X-1000159Y-64748D01*
G37*
G36*
G01X-1003593Y-52047D02*
X-1000064Y-50303D01*
X-999071Y-50689D01*
X-997850Y-53160D01*
X-998682Y-55766D01*
X-1000094Y-56464D01*
X-1002669Y-55541D01*
X-1003890Y-53070D01*
X-1003593Y-52047D01*
G37*
G36*
G01X-1000159Y-79708D02*
X-1003727Y-81372D01*
X-1004711Y-80964D01*
X-1005876Y-78466D01*
X-1004986Y-75879D01*
X-1003558Y-75214D01*
X-1001004Y-76194D01*
X-999840Y-78692D01*
X-1000159Y-79708D01*
G37*
G36*
G01X-1003593Y-81968D02*
X-1000064Y-80224D01*
X-999071Y-80610D01*
X-997850Y-83081D01*
X-998682Y-85687D01*
X-1000094Y-86385D01*
X-1002669Y-85462D01*
X-1003890Y-82991D01*
X-1003593Y-81968D01*
G37*
G36*
G01Y-67007D02*
X-1000064Y-65263D01*
X-999071Y-65650D01*
X-997850Y-68121D01*
X-998682Y-70727D01*
X-1000094Y-71424D01*
X-1002669Y-70501D01*
X-1003890Y-68030D01*
X-1003593Y-67007D01*
G37*
G36*
G01X-1000159Y-94669D02*
X-1003727Y-96333D01*
X-1004711Y-95924D01*
X-1005876Y-93427D01*
X-1004986Y-90840D01*
X-1003558Y-90174D01*
X-1001004Y-91155D01*
X-999840Y-93653D01*
X-1000159Y-94669D01*
G37*
G36*
G01X-1003593Y-96928D02*
X-1000064Y-95185D01*
X-999071Y-95571D01*
X-997850Y-98042D01*
X-998682Y-100648D01*
X-1000094Y-101346D01*
X-1002669Y-100423D01*
X-1003890Y-97952D01*
X-1003593Y-96928D01*
G37*
G36*
G01X-1009017Y-49787D02*
X-1012586Y-51451D01*
X-1013569Y-51043D01*
X-1014734Y-48545D01*
X-1013844Y-45958D01*
X-1012416Y-45293D01*
X-1009863Y-46273D01*
X-1008698Y-48771D01*
X-1009017Y-49787D01*
G37*
G36*
G01Y-64748D02*
X-1012586Y-66412D01*
X-1013569Y-66003D01*
X-1014734Y-63505D01*
X-1013844Y-60919D01*
X-1012416Y-60253D01*
X-1009863Y-61234D01*
X-1008698Y-63732D01*
X-1009017Y-64748D01*
G37*
G36*
G01X-1012452Y-52047D02*
X-1008922Y-50303D01*
X-1007929Y-50689D01*
X-1006708Y-53160D01*
X-1007540Y-55766D01*
X-1008952Y-56464D01*
X-1011527Y-55541D01*
X-1012748Y-53070D01*
X-1012452Y-52047D01*
G37*
G36*
G01Y-67007D02*
X-1008922Y-65263D01*
X-1007929Y-65650D01*
X-1006708Y-68121D01*
X-1007540Y-70727D01*
X-1008952Y-71424D01*
X-1011527Y-70501D01*
X-1012748Y-68030D01*
X-1012452Y-67007D01*
G37*
G36*
G01Y-81968D02*
X-1008922Y-80224D01*
X-1007929Y-80610D01*
X-1006708Y-83081D01*
X-1007540Y-85687D01*
X-1008952Y-86385D01*
X-1011527Y-85462D01*
X-1012748Y-82991D01*
X-1012452Y-81968D01*
G37*
G36*
G01X-1009017Y-79708D02*
X-1012586Y-81372D01*
X-1013569Y-80964D01*
X-1014734Y-78466D01*
X-1013844Y-75879D01*
X-1012416Y-75214D01*
X-1009863Y-76194D01*
X-1008698Y-78692D01*
X-1009017Y-79708D01*
G37*
G36*
G01X-1012452Y-96928D02*
X-1008922Y-95185D01*
X-1007929Y-95571D01*
X-1006708Y-98042D01*
X-1007540Y-100648D01*
X-1008952Y-101346D01*
X-1011527Y-100423D01*
X-1012748Y-97952D01*
X-1012452Y-96928D01*
G37*
G36*
G01X-1009017Y-94669D02*
X-1012586Y-96333D01*
X-1013569Y-95924D01*
X-1014734Y-93427D01*
X-1013844Y-90840D01*
X-1012416Y-90174D01*
X-1009863Y-91155D01*
X-1008698Y-93653D01*
X-1009017Y-94669D01*
G37*
G36*
G01X-1099250Y-137850D02*
Y-146850D01*
X-1100250Y-147850D01*
X-1105650D01*
X-1106650Y-146850D01*
Y-137850D01*
X-1105650Y-136850D01*
X-1100250D01*
X-1099250Y-137850D01*
G37*
G36*
G01X-1118148D02*
Y-146850D01*
X-1119148Y-147850D01*
X-1124548D01*
X-1125548Y-146850D01*
Y-137850D01*
X-1124548Y-136850D01*
X-1119148D01*
X-1118148Y-137850D01*
G37*
G36*
G01X-1167283Y-80818D02*
Y-92362D01*
G02X-1190669I-11693J0D01*
G01Y-80818D01*
G02X-1167283I11693J12078D01*
G37*
G36*
G01X-1411378Y-134126D02*
Y-145669D01*
G02X-1434764I-11693J0D01*
G01Y-134126D01*
G02X-1411378I11693J12078D01*
G37*
G36*
G01X-1631850Y-63259D02*
Y-74803D01*
G02X-1655236I-11693J0D01*
G01Y-63259D01*
G02X-1631850I11693J12078D01*
G37*
G36*
G01X-593212Y-86800D02*
X-593211Y-86793D01*
Y-81986D01*
X-593212Y-81979D01*
G02X-590029Y-81674I1598J90D01*
G01X-590011Y-81803D01*
Y-86977D01*
X-590029Y-87106D01*
G02X-593212Y-86800I-1585J216D01*
G37*
G36*
G01X-603212D02*
X-603211Y-86793D01*
Y-81986D01*
X-603212Y-81979D01*
G02X-600029Y-81674I1598J90D01*
G01X-600011Y-81803D01*
Y-86977D01*
X-600029Y-87106D01*
G02X-603212Y-86800I-1585J216D01*
G37*
G36*
G01X-613212D02*
X-613211Y-86793D01*
Y-81986D01*
X-613212Y-81979D01*
G02X-610029Y-81674I1598J90D01*
G01X-610011Y-81803D01*
Y-86977D01*
X-610029Y-87106D01*
G02X-613212Y-86800I-1585J216D01*
G37*
G36*
G01X-1463290D02*
X-1463290Y-86793D01*
Y-81986D01*
X-1463290Y-81979D01*
G02X-1460108Y-81674I1598J90D01*
G01X-1460090Y-81803D01*
Y-86977D01*
X-1460108Y-87106D01*
G02X-1463290Y-86800I-1585J216D01*
G37*
G36*
G01X-1473290D02*
X-1473290Y-86793D01*
Y-81986D01*
X-1473290Y-81979D01*
G02X-1470108Y-81674I1598J90D01*
G01X-1470090Y-81803D01*
Y-86977D01*
X-1470108Y-87106D01*
G02X-1473290Y-86800I-1585J216D01*
G37*
G36*
G01X-1483290D02*
X-1483290Y-86793D01*
Y-81986D01*
X-1483290Y-81979D01*
G02X-1480108Y-81674I1598J90D01*
G01X-1480090Y-81803D01*
Y-86977D01*
X-1480108Y-87106D01*
G02X-1483290Y-86800I-1585J216D01*
G37*
G36*
G01X-598212Y-96800D02*
X-598211Y-96793D01*
Y-91986D01*
X-598212Y-91979D01*
G02X-595029Y-91674I1598J90D01*
G01X-595011Y-91803D01*
Y-96977D01*
X-595029Y-97106D01*
G02X-598212Y-96800I-1585J216D01*
G37*
G36*
G01X-608212D02*
X-608211Y-96793D01*
Y-91986D01*
X-608212Y-91979D01*
G02X-605029Y-91674I1598J90D01*
G01X-605011Y-91803D01*
Y-96977D01*
X-605029Y-97106D01*
G02X-608212Y-96800I-1585J216D01*
G37*
G36*
G01X-618212D02*
X-618211Y-96793D01*
Y-91986D01*
X-618212Y-91979D01*
G02X-615029Y-91674I1598J90D01*
G01X-615011Y-91803D01*
Y-96977D01*
X-615029Y-97106D01*
G02X-618212Y-96800I-1585J216D01*
G37*
G36*
G01X-1468290D02*
X-1468290Y-96793D01*
Y-91986D01*
X-1468290Y-91979D01*
G02X-1465108Y-91674I1598J90D01*
G01X-1465090Y-91803D01*
Y-96977D01*
X-1465108Y-97106D01*
G02X-1468290Y-96800I-1585J216D01*
G37*
G36*
G01X-1478290D02*
X-1478290Y-96793D01*
Y-91986D01*
X-1478290Y-91979D01*
G02X-1475108Y-91674I1598J90D01*
G01X-1475090Y-91803D01*
Y-96977D01*
X-1475108Y-97106D01*
G02X-1478290Y-96800I-1585J216D01*
G37*
G36*
G01X-1488290D02*
X-1488290Y-96793D01*
Y-91986D01*
X-1488290Y-91979D01*
G02X-1485108Y-91674I1598J90D01*
G01X-1485090Y-91803D01*
Y-96977D01*
X-1485108Y-97106D01*
G02X-1488290Y-96800I-1585J216D01*
G37*
G36*
G01X-593212Y-106800D02*
X-593211Y-106793D01*
Y-101986D01*
X-593212Y-101979D01*
G02X-590029Y-101674I1598J90D01*
G01X-590011Y-101803D01*
Y-106977D01*
X-590029Y-107106D01*
G02X-593212Y-106800I-1585J216D01*
G37*
G36*
G01X-603212D02*
X-603211Y-106793D01*
Y-101986D01*
X-603212Y-101979D01*
G02X-600029Y-101674I1598J90D01*
G01X-600011Y-101803D01*
Y-106977D01*
X-600029Y-107106D01*
G02X-603212Y-106800I-1585J216D01*
G37*
G36*
G01X-613212D02*
X-613211Y-106793D01*
Y-101986D01*
X-613212Y-101979D01*
G02X-610029Y-101674I1598J90D01*
G01X-610011Y-101803D01*
Y-106977D01*
X-610029Y-107106D01*
G02X-613212Y-106800I-1585J216D01*
G37*
G36*
G01X-1463290D02*
X-1463290Y-106793D01*
Y-101986D01*
X-1463290Y-101979D01*
G02X-1460108Y-101674I1598J90D01*
G01X-1460090Y-101803D01*
Y-106977D01*
X-1460108Y-107106D01*
G02X-1463290Y-106800I-1585J216D01*
G37*
G36*
G01X-1473290D02*
X-1473290Y-106793D01*
Y-101986D01*
X-1473290Y-101979D01*
G02X-1470108Y-101674I1598J90D01*
G01X-1470090Y-101803D01*
Y-106977D01*
X-1470108Y-107106D01*
G02X-1473290Y-106800I-1585J216D01*
G37*
G36*
G01X-1483290D02*
X-1483290Y-106793D01*
Y-101986D01*
X-1483290Y-101979D01*
G02X-1480108Y-101674I1598J90D01*
G01X-1480090Y-101803D01*
Y-106977D01*
X-1480108Y-107106D01*
G02X-1483290Y-106800I-1585J216D01*
G37*
G36*
G01X-680665Y-108132D02*
Y-110173D01*
X-685165D01*
Y-108126D01*
G02Y-105732I2252J1197D01*
G01Y-102614D01*
G02Y-100221I2252J1197D01*
G01Y-98173D01*
X-680665D01*
Y-100214D01*
G02Y-102621I-2248J-1203D01*
G01Y-105726D01*
G02Y-108132I-2248J-1203D01*
G37*
G36*
G01X-696413D02*
Y-110173D01*
X-700913D01*
Y-108126D01*
G02Y-105732I2252J1197D01*
G01Y-102614D01*
G02Y-100221I2252J1197D01*
G01Y-98173D01*
X-696413D01*
Y-100214D01*
G02Y-102621I-2248J-1203D01*
G01Y-105726D01*
G02Y-108132I-2248J-1203D01*
G37*
G36*
G01X-712161D02*
Y-110173D01*
X-716661D01*
Y-108126D01*
G02Y-105732I2252J1197D01*
G01Y-102614D01*
G02Y-100221I2252J1197D01*
G01Y-98173D01*
X-712161D01*
Y-100214D01*
G02Y-102621I-2248J-1203D01*
G01Y-105726D01*
G02Y-108132I-2248J-1203D01*
G37*
G36*
G01X-727909D02*
Y-110173D01*
X-732409D01*
Y-108126D01*
G02Y-105732I2252J1197D01*
G01Y-102614D01*
G02Y-100221I2252J1197D01*
G01Y-98173D01*
X-727909D01*
Y-100214D01*
G02Y-102621I-2248J-1203D01*
G01Y-105726D01*
G02Y-108132I-2248J-1203D01*
G37*
G36*
G01X-1550744D02*
Y-110173D01*
X-1555244D01*
Y-108126D01*
G02Y-105732I2252J1197D01*
G01Y-102614D01*
G02Y-100221I2252J1197D01*
G01Y-98173D01*
X-1550744D01*
Y-100214D01*
G02Y-102621I-2248J-1203D01*
G01Y-105726D01*
G02Y-108132I-2248J-1203D01*
G37*
G36*
G01X-1566492D02*
Y-110173D01*
X-1570992D01*
Y-108126D01*
G02Y-105732I2252J1197D01*
G01Y-102614D01*
G02Y-100221I2252J1197D01*
G01Y-98173D01*
X-1566492D01*
Y-100214D01*
G02Y-102621I-2248J-1203D01*
G01Y-105726D01*
G02Y-108132I-2248J-1203D01*
G37*
G36*
G01X-1582240D02*
Y-110173D01*
X-1586740D01*
Y-108126D01*
G02Y-105732I2252J1197D01*
G01Y-102614D01*
G02Y-100221I2252J1197D01*
G01Y-98173D01*
X-1582240D01*
Y-100214D01*
G02Y-102621I-2248J-1203D01*
G01Y-105726D01*
G02Y-108132I-2248J-1203D01*
G37*
G36*
G01X-1597988D02*
Y-110173D01*
X-1602488D01*
Y-108126D01*
G02Y-105732I2252J1197D01*
G01Y-102614D01*
G02Y-100221I2252J1197D01*
G01Y-98173D01*
X-1597988D01*
Y-100214D01*
G02Y-102621I-2248J-1203D01*
G01Y-105726D01*
G02Y-108132I-2248J-1203D01*
G37*
G36*
G01X-672791Y-113250D02*
Y-115291D01*
X-677291D01*
Y-113244D01*
G02Y-110850I2252J1197D01*
G01Y-107732D01*
G02Y-105339I2252J1197D01*
G01Y-103291D01*
X-672791D01*
Y-105332D01*
G02Y-107739I-2248J-1203D01*
G01Y-110844D01*
G02Y-113250I-2248J-1203D01*
G37*
G36*
G01X-688539D02*
Y-115291D01*
X-693039D01*
Y-113244D01*
G02Y-110850I2252J1197D01*
G01Y-107732D01*
G02Y-105339I2252J1197D01*
G01Y-103291D01*
X-688539D01*
Y-105332D01*
G02Y-107739I-2248J-1203D01*
G01Y-110844D01*
G02Y-113250I-2248J-1203D01*
G37*
G36*
G01X-704287D02*
Y-115291D01*
X-708787D01*
Y-113244D01*
G02Y-110850I2252J1197D01*
G01Y-107732D01*
G02Y-105339I2252J1197D01*
G01Y-103291D01*
X-704287D01*
Y-105332D01*
G02Y-107739I-2248J-1203D01*
G01Y-110844D01*
G02Y-113250I-2248J-1203D01*
G37*
G36*
G01X-720035D02*
Y-115291D01*
X-724535D01*
Y-113244D01*
G02Y-110850I2252J1197D01*
G01Y-107732D01*
G02Y-105339I2252J1197D01*
G01Y-103291D01*
X-720035D01*
Y-105332D01*
G02Y-107739I-2248J-1203D01*
G01Y-110844D01*
G02Y-113250I-2248J-1203D01*
G37*
G36*
G01X-1542870D02*
Y-115291D01*
X-1547370D01*
Y-113244D01*
G02Y-110850I2252J1197D01*
G01Y-107732D01*
G02Y-105339I2252J1197D01*
G01Y-103291D01*
X-1542870D01*
Y-105332D01*
G02Y-107739I-2248J-1203D01*
G01Y-110844D01*
G02Y-113250I-2248J-1203D01*
G37*
G36*
G01X-1558618D02*
Y-115291D01*
X-1563118D01*
Y-113244D01*
G02Y-110850I2252J1197D01*
G01Y-107732D01*
G02Y-105339I2252J1197D01*
G01Y-103291D01*
X-1558618D01*
Y-105332D01*
G02Y-107739I-2248J-1203D01*
G01Y-110844D01*
G02Y-113250I-2248J-1203D01*
G37*
G36*
G01X-1574366D02*
Y-115291D01*
X-1578866D01*
Y-113244D01*
G02Y-110850I2252J1197D01*
G01Y-107732D01*
G02Y-105339I2252J1197D01*
G01Y-103291D01*
X-1574366D01*
Y-105332D01*
G02Y-107739I-2248J-1203D01*
G01Y-110844D01*
G02Y-113250I-2248J-1203D01*
G37*
G36*
G01X-1590114D02*
Y-115291D01*
X-1594614D01*
Y-113244D01*
G02Y-110850I2252J1197D01*
G01Y-107732D01*
G02Y-105339I2252J1197D01*
G01Y-103291D01*
X-1590114D01*
Y-105332D01*
G02Y-107739I-2248J-1203D01*
G01Y-110844D01*
G02Y-113250I-2248J-1203D01*
G37*
G36*
G01X-598212Y-116800D02*
X-598211Y-116793D01*
Y-111986D01*
X-598212Y-111979D01*
G02X-595029Y-111674I1598J90D01*
G01X-595011Y-111803D01*
Y-116977D01*
X-595029Y-117106D01*
G02X-598212Y-116800I-1585J216D01*
G37*
G36*
G01X-608212D02*
X-608211Y-116793D01*
Y-111986D01*
X-608212Y-111979D01*
G02X-605029Y-111674I1598J90D01*
G01X-605011Y-111803D01*
Y-116977D01*
X-605029Y-117106D01*
G02X-608212Y-116800I-1585J216D01*
G37*
G36*
G01X-618212D02*
X-618211Y-116793D01*
Y-111986D01*
X-618212Y-111979D01*
G02X-615029Y-111674I1598J90D01*
G01X-615011Y-111803D01*
Y-116977D01*
X-615029Y-117106D01*
G02X-618212Y-116800I-1585J216D01*
G37*
G36*
G01X-1468290D02*
X-1468290Y-116793D01*
Y-111986D01*
X-1468290Y-111979D01*
G02X-1465108Y-111674I1598J90D01*
G01X-1465090Y-111803D01*
Y-116977D01*
X-1465108Y-117106D01*
G02X-1468290Y-116800I-1585J216D01*
G37*
G36*
G01X-1478290D02*
X-1478290Y-116793D01*
Y-111986D01*
X-1478290Y-111979D01*
G02X-1475108Y-111674I1598J90D01*
G01X-1475090Y-111803D01*
Y-116977D01*
X-1475108Y-117106D01*
G02X-1478290Y-116800I-1585J216D01*
G37*
G36*
G01X-1488290D02*
X-1488290Y-116793D01*
Y-111986D01*
X-1488290Y-111979D01*
G02X-1485108Y-111674I1598J90D01*
G01X-1485090Y-111803D01*
Y-116977D01*
X-1485108Y-117106D01*
G02X-1488290Y-116800I-1585J216D01*
G37*
G36*
G01X-240725Y-121879D02*
X-240744Y-121702D01*
Y-118409D01*
X-240725Y-118232D01*
G02X-236543Y-118618I2088J-223D01*
G01X-236544Y-118627D01*
Y-121483D01*
X-236543Y-121493D01*
G02X-240725Y-121879I-2094J-162D01*
G37*
G36*
G01X-1110804D02*
X-1110823Y-121702D01*
Y-118409D01*
X-1110804Y-118232D01*
G02X-1106622Y-118618I2088J-223D01*
G01X-1106623Y-118627D01*
Y-121483D01*
X-1106622Y-121493D01*
G02X-1110804Y-121879I-2094J-162D01*
G37*
G36*
G01X-680665Y-124668D02*
Y-126709D01*
X-685165D01*
Y-124661D01*
G02Y-122268I2252J1197D01*
G01Y-119150D01*
G02Y-116756I2252J1197D01*
G01Y-114709D01*
X-680665D01*
Y-116750D01*
G02Y-119156I-2248J-1203D01*
G01Y-122261D01*
G02Y-124668I-2248J-1203D01*
G37*
G36*
G01X-696413D02*
Y-126709D01*
X-700913D01*
Y-124661D01*
G02Y-122268I2252J1197D01*
G01Y-119150D01*
G02Y-116756I2252J1197D01*
G01Y-114709D01*
X-696413D01*
Y-116750D01*
G02Y-119156I-2248J-1203D01*
G01Y-122261D01*
G02Y-124668I-2248J-1203D01*
G37*
G36*
G01X-712161D02*
Y-126709D01*
X-716661D01*
Y-124661D01*
G02Y-122268I2252J1197D01*
G01Y-119150D01*
G02Y-116756I2252J1197D01*
G01Y-114709D01*
X-712161D01*
Y-116750D01*
G02Y-119156I-2248J-1203D01*
G01Y-122261D01*
G02Y-124668I-2248J-1203D01*
G37*
G36*
G01X-727909D02*
Y-126709D01*
X-732409D01*
Y-124661D01*
G02Y-122268I2252J1197D01*
G01Y-119150D01*
G02Y-116756I2252J1197D01*
G01Y-114709D01*
X-727909D01*
Y-116750D01*
G02Y-119156I-2248J-1203D01*
G01Y-122261D01*
G02Y-124668I-2248J-1203D01*
G37*
G36*
G01X-1550744D02*
Y-126709D01*
X-1555244D01*
Y-124661D01*
G02Y-122268I2252J1197D01*
G01Y-119150D01*
G02Y-116756I2252J1197D01*
G01Y-114709D01*
X-1550744D01*
Y-116750D01*
G02Y-119156I-2248J-1203D01*
G01Y-122261D01*
G02Y-124668I-2248J-1203D01*
G37*
G36*
G01X-1566492D02*
Y-126709D01*
X-1570992D01*
Y-124661D01*
G02Y-122268I2252J1197D01*
G01Y-119150D01*
G02Y-116756I2252J1197D01*
G01Y-114709D01*
X-1566492D01*
Y-116750D01*
G02Y-119156I-2248J-1203D01*
G01Y-122261D01*
G02Y-124668I-2248J-1203D01*
G37*
G36*
G01X-1582240D02*
Y-126709D01*
X-1586740D01*
Y-124661D01*
G02Y-122268I2252J1197D01*
G01Y-119150D01*
G02Y-116756I2252J1197D01*
G01Y-114709D01*
X-1582240D01*
Y-116750D01*
G02Y-119156I-2248J-1203D01*
G01Y-122261D01*
G02Y-124668I-2248J-1203D01*
G37*
G36*
G01X-1597988D02*
Y-126709D01*
X-1602488D01*
Y-124661D01*
G02Y-122268I2252J1197D01*
G01Y-119150D01*
G02Y-116756I2252J1197D01*
G01Y-114709D01*
X-1597988D01*
Y-116750D01*
G02Y-119156I-2248J-1203D01*
G01Y-122261D01*
G02Y-124668I-2248J-1203D01*
G37*
G36*
G01X-1347998Y-116208D02*
G02X-1347689Y-120301I-8891J-2729D01*
G02X-1347998Y-116208I-9199J1364D01*
G37*
G36*
G01X-593212Y-126800D02*
X-593211Y-126793D01*
Y-121986D01*
X-593212Y-121979D01*
G02X-590029Y-121674I1598J90D01*
G01X-590011Y-121803D01*
Y-126977D01*
X-590029Y-127106D01*
G02X-593212Y-126800I-1585J216D01*
G37*
G36*
G01X-603212D02*
X-603211Y-126793D01*
Y-121986D01*
X-603212Y-121979D01*
G02X-600029Y-121674I1598J90D01*
G01X-600011Y-121803D01*
Y-126977D01*
X-600029Y-127106D01*
G02X-603212Y-126800I-1585J216D01*
G37*
G36*
G01X-613212D02*
X-613211Y-126793D01*
Y-121986D01*
X-613212Y-121979D01*
G02X-610029Y-121674I1598J90D01*
G01X-610011Y-121803D01*
Y-126977D01*
X-610029Y-127106D01*
G02X-613212Y-126800I-1585J216D01*
G37*
G36*
G01X-1463290D02*
X-1463290Y-126793D01*
Y-121986D01*
X-1463290Y-121979D01*
G02X-1460108Y-121674I1598J90D01*
G01X-1460090Y-121803D01*
Y-126977D01*
X-1460108Y-127106D01*
G02X-1463290Y-126800I-1585J216D01*
G37*
G36*
G01X-1473290D02*
X-1473290Y-126793D01*
Y-121986D01*
X-1473290Y-121979D01*
G02X-1470108Y-121674I1598J90D01*
G01X-1470090Y-121803D01*
Y-126977D01*
X-1470108Y-127106D01*
G02X-1473290Y-126800I-1585J216D01*
G37*
G36*
G01X-1483290D02*
X-1483290Y-126793D01*
Y-121986D01*
X-1483290Y-121979D01*
G02X-1480108Y-121674I1598J90D01*
G01X-1480090Y-121803D01*
Y-126977D01*
X-1480108Y-127106D01*
G02X-1483290Y-126800I-1585J216D01*
G37*
G36*
G01X-672791Y-129786D02*
Y-131827D01*
X-677291D01*
Y-129779D01*
G02Y-127386I2252J1197D01*
G01Y-124268D01*
G02Y-121874I2252J1197D01*
G01Y-119827D01*
X-672791D01*
Y-121868D01*
G02Y-124274I-2248J-1203D01*
G01Y-127379D01*
G02Y-129786I-2248J-1203D01*
G37*
G36*
G01X-688539D02*
Y-131827D01*
X-693039D01*
Y-129779D01*
G02Y-127386I2252J1197D01*
G01Y-124268D01*
G02Y-121874I2252J1197D01*
G01Y-119827D01*
X-688539D01*
Y-121868D01*
G02Y-124274I-2248J-1203D01*
G01Y-127379D01*
G02Y-129786I-2248J-1203D01*
G37*
G36*
G01X-704287D02*
Y-131827D01*
X-708787D01*
Y-129779D01*
G02Y-127386I2252J1197D01*
G01Y-124268D01*
G02Y-121874I2252J1197D01*
G01Y-119827D01*
X-704287D01*
Y-121868D01*
G02Y-124274I-2248J-1203D01*
G01Y-127379D01*
G02Y-129786I-2248J-1203D01*
G37*
G36*
G01X-720035D02*
Y-131827D01*
X-724535D01*
Y-129779D01*
G02Y-127386I2252J1197D01*
G01Y-124268D01*
G02Y-121874I2252J1197D01*
G01Y-119827D01*
X-720035D01*
Y-121868D01*
G02Y-124274I-2248J-1203D01*
G01Y-127379D01*
G02Y-129786I-2248J-1203D01*
G37*
G36*
G01X-735783D02*
Y-131827D01*
X-740283D01*
Y-129779D01*
G02Y-127386I2252J1197D01*
G01Y-124268D01*
G02Y-121874I2252J1197D01*
G01Y-119827D01*
X-735783D01*
Y-121868D01*
G02Y-124274I-2248J-1203D01*
G01Y-127379D01*
G02Y-129786I-2248J-1203D01*
G37*
G36*
G01X-1542870D02*
Y-131827D01*
X-1547370D01*
Y-129779D01*
G02Y-127386I2252J1197D01*
G01Y-124268D01*
G02Y-121874I2252J1197D01*
G01Y-119827D01*
X-1542870D01*
Y-121868D01*
G02Y-124274I-2248J-1203D01*
G01Y-127379D01*
G02Y-129786I-2248J-1203D01*
G37*
G36*
G01X-1558618D02*
Y-131827D01*
X-1563118D01*
Y-129779D01*
G02Y-127386I2252J1197D01*
G01Y-124268D01*
G02Y-121874I2252J1197D01*
G01Y-119827D01*
X-1558618D01*
Y-121868D01*
G02Y-124274I-2248J-1203D01*
G01Y-127379D01*
G02Y-129786I-2248J-1203D01*
G37*
G36*
G01X-1574366D02*
Y-131827D01*
X-1578866D01*
Y-129779D01*
G02Y-127386I2252J1197D01*
G01Y-124268D01*
G02Y-121874I2252J1197D01*
G01Y-119827D01*
X-1574366D01*
Y-121868D01*
G02Y-124274I-2248J-1203D01*
G01Y-127379D01*
G02Y-129786I-2248J-1203D01*
G37*
G36*
G01X-1590114D02*
Y-131827D01*
X-1594614D01*
Y-129779D01*
G02Y-127386I2252J1197D01*
G01Y-124268D01*
G02Y-121874I2252J1197D01*
G01Y-119827D01*
X-1590114D01*
Y-121868D01*
G02Y-124274I-2248J-1203D01*
G01Y-127379D01*
G02Y-129786I-2248J-1203D01*
G37*
G36*
G01X-1605862D02*
Y-131827D01*
X-1610362D01*
Y-129779D01*
G02Y-127386I2252J1197D01*
G01Y-124268D01*
G02Y-121874I2252J1197D01*
G01Y-119827D01*
X-1605862D01*
Y-121868D01*
G02Y-124274I-2248J-1203D01*
G01Y-127379D01*
G02Y-129786I-2248J-1203D01*
G37*
G36*
G01X-363438Y-132269D02*
X-363260Y-132250D01*
X-359968D01*
X-359791Y-132269D01*
G02X-360176Y-136451I-223J-2088D01*
G01X-360186Y-136450D01*
X-363042D01*
X-363051Y-136451D01*
G02X-363438Y-132269I-162J2094D01*
G37*
G36*
G01X-1233516D02*
X-1233339Y-132250D01*
X-1230046D01*
X-1229869Y-132269D01*
G02X-1230255Y-136451I-223J-2088D01*
G01X-1230265Y-136450D01*
X-1233120D01*
X-1233130Y-136451D01*
G02X-1233516Y-132269I-162J2094D01*
G37*
G36*
G01X-598212Y-136800D02*
X-598211Y-136793D01*
Y-131986D01*
X-598212Y-131979D01*
G02X-595029Y-131674I1598J90D01*
G01X-595011Y-131803D01*
Y-136977D01*
X-595029Y-137106D01*
G02X-598212Y-136800I-1585J216D01*
G37*
G36*
G01X-608212D02*
X-608211Y-136793D01*
Y-131986D01*
X-608212Y-131979D01*
G02X-605029Y-131674I1598J90D01*
G01X-605011Y-131803D01*
Y-136977D01*
X-605029Y-137106D01*
G02X-608212Y-136800I-1585J216D01*
G37*
G36*
G01X-618212D02*
X-618211Y-136793D01*
Y-131986D01*
X-618212Y-131979D01*
G02X-615029Y-131674I1598J90D01*
G01X-615011Y-131803D01*
Y-136977D01*
X-615029Y-137106D01*
G02X-618212Y-136800I-1585J216D01*
G37*
G36*
G01X-1468290D02*
X-1468290Y-136793D01*
Y-131986D01*
X-1468290Y-131979D01*
G02X-1465108Y-131674I1598J90D01*
G01X-1465090Y-131803D01*
Y-136977D01*
X-1465108Y-137106D01*
G02X-1468290Y-136800I-1585J216D01*
G37*
G36*
G01X-1478290D02*
X-1478290Y-136793D01*
Y-131986D01*
X-1478290Y-131979D01*
G02X-1475108Y-131674I1598J90D01*
G01X-1475090Y-131803D01*
Y-136977D01*
X-1475108Y-137106D01*
G02X-1478290Y-136800I-1585J216D01*
G37*
G36*
G01X-1488290D02*
X-1488290Y-136793D01*
Y-131986D01*
X-1488290Y-131979D01*
G02X-1485108Y-131674I1598J90D01*
G01X-1485090Y-131803D01*
Y-136977D01*
X-1485108Y-137106D01*
G02X-1488290Y-136800I-1585J216D01*
G37*
G36*
G01X-680665Y-141203D02*
Y-143244D01*
X-685165D01*
Y-141197D01*
G02Y-138803I2252J1197D01*
G01Y-135685D01*
G02Y-133291I2252J1197D01*
G01Y-131244D01*
X-680665D01*
Y-133285D01*
G02Y-135691I-2248J-1203D01*
G01Y-138797D01*
G02Y-141203I-2248J-1203D01*
G37*
G36*
G01X-696413D02*
Y-143244D01*
X-700913D01*
Y-141197D01*
G02Y-138803I2252J1197D01*
G01Y-135685D01*
G02Y-133291I2252J1197D01*
G01Y-131244D01*
X-696413D01*
Y-133285D01*
G02Y-135691I-2248J-1203D01*
G01Y-138797D01*
G02Y-141203I-2248J-1203D01*
G37*
G36*
G01X-712161D02*
Y-143244D01*
X-716661D01*
Y-141197D01*
G02Y-138803I2252J1197D01*
G01Y-135685D01*
G02Y-133291I2252J1197D01*
G01Y-131244D01*
X-712161D01*
Y-133285D01*
G02Y-135691I-2248J-1203D01*
G01Y-138797D01*
G02Y-141203I-2248J-1203D01*
G37*
G36*
G01X-727909D02*
Y-143244D01*
X-732409D01*
Y-141197D01*
G02Y-138803I2252J1197D01*
G01Y-135685D01*
G02Y-133291I2252J1197D01*
G01Y-131244D01*
X-727909D01*
Y-133285D01*
G02Y-135691I-2248J-1203D01*
G01Y-138797D01*
G02Y-141203I-2248J-1203D01*
G37*
G36*
G01X-1550744D02*
Y-143244D01*
X-1555244D01*
Y-141197D01*
G02Y-138803I2252J1197D01*
G01Y-135685D01*
G02Y-133291I2252J1197D01*
G01Y-131244D01*
X-1550744D01*
Y-133285D01*
G02Y-135691I-2248J-1203D01*
G01Y-138797D01*
G02Y-141203I-2248J-1203D01*
G37*
G36*
G01X-1566492D02*
Y-143244D01*
X-1570992D01*
Y-141197D01*
G02Y-138803I2252J1197D01*
G01Y-135685D01*
G02Y-133291I2252J1197D01*
G01Y-131244D01*
X-1566492D01*
Y-133285D01*
G02Y-135691I-2248J-1203D01*
G01Y-138797D01*
G02Y-141203I-2248J-1203D01*
G37*
G36*
G01X-1582240D02*
Y-143244D01*
X-1586740D01*
Y-141197D01*
G02Y-138803I2252J1197D01*
G01Y-135685D01*
G02Y-133291I2252J1197D01*
G01Y-131244D01*
X-1582240D01*
Y-133285D01*
G02Y-135691I-2248J-1203D01*
G01Y-138797D01*
G02Y-141203I-2248J-1203D01*
G37*
G36*
G01X-1597988D02*
Y-143244D01*
X-1602488D01*
Y-141197D01*
G02Y-138803I2252J1197D01*
G01Y-135685D01*
G02Y-133291I2252J1197D01*
G01Y-131244D01*
X-1597988D01*
Y-133285D01*
G02Y-135691I-2248J-1203D01*
G01Y-138797D01*
G02Y-141203I-2248J-1203D01*
G37*
G36*
G01X-324681Y-141597D02*
Y-143638D01*
X-329181D01*
Y-141590D01*
G02Y-139197I2252J1197D01*
G01Y-136079D01*
G02Y-133685I2252J1197D01*
G01Y-131638D01*
X-324681D01*
Y-133679D01*
G02Y-136085I-2248J-1203D01*
G01Y-139190D01*
G02Y-141597I-2248J-1203D01*
G37*
G36*
G01X-1194760D02*
Y-143638D01*
X-1199260D01*
Y-141590D01*
G02Y-139197I2252J1197D01*
G01Y-136079D01*
G02Y-133685I2252J1197D01*
G01Y-131638D01*
X-1194760D01*
Y-133679D01*
G02Y-136085I-2248J-1203D01*
G01Y-139190D01*
G02Y-141597I-2248J-1203D01*
G37*
G36*
G01X-110663Y-141594D02*
Y-143638D01*
X-115163D01*
Y-141594D01*
G02Y-139194I2250J1200D01*
G01Y-136082D01*
G02Y-133682I2250J1200D01*
G01Y-131638D01*
X-110663D01*
Y-133682D01*
G02Y-136082I-2250J-1200D01*
G01Y-139194D01*
G02Y-141594I-2250J-1200D01*
G37*
G36*
G01X-126411D02*
Y-143638D01*
X-130911D01*
Y-141594D01*
G02Y-139194I2250J1200D01*
G01Y-136082D01*
G02Y-133682I2250J1200D01*
G01Y-131638D01*
X-126411D01*
Y-133682D01*
G02Y-136082I-2250J-1200D01*
G01Y-139194D01*
G02Y-141594I-2250J-1200D01*
G37*
G36*
G01X-142159D02*
Y-143638D01*
X-146659D01*
Y-141594D01*
G02Y-139194I2250J1200D01*
G01Y-136082D01*
G02Y-133682I2250J1200D01*
G01Y-131638D01*
X-142159D01*
Y-133682D01*
G02Y-136082I-2250J-1200D01*
G01Y-139194D01*
G02Y-141594I-2250J-1200D01*
G37*
G36*
G01X-980742D02*
Y-143638D01*
X-985242D01*
Y-141594D01*
G02Y-139194I2250J1200D01*
G01Y-136082D01*
G02Y-133682I2250J1200D01*
G01Y-131638D01*
X-980742D01*
Y-133682D01*
G02Y-136082I-2250J-1200D01*
G01Y-139194D01*
G02Y-141594I-2250J-1200D01*
G37*
G36*
G01X-996490D02*
Y-143638D01*
X-1000990D01*
Y-141594D01*
G02Y-139194I2250J1200D01*
G01Y-136082D01*
G02Y-133682I2250J1200D01*
G01Y-131638D01*
X-996490D01*
Y-133682D01*
G02Y-136082I-2250J-1200D01*
G01Y-139194D01*
G02Y-141594I-2250J-1200D01*
G37*
G36*
G01X-1012238D02*
Y-143638D01*
X-1016738D01*
Y-141594D01*
G02Y-139194I2250J1200D01*
G01Y-136082D01*
G02Y-133682I2250J1200D01*
G01Y-131638D01*
X-1012238D01*
Y-133682D01*
G02Y-136082I-2250J-1200D01*
G01Y-139194D01*
G02Y-141594I-2250J-1200D01*
G37*
G36*
G01X-391770Y-142354D02*
X-391593Y-142335D01*
X-388300D01*
X-388123Y-142354D01*
G02X-388509Y-146536I-223J-2088D01*
G01X-388518Y-146535D01*
X-391374D01*
X-391384Y-146536D01*
G02X-391770Y-142354I-162J2094D01*
G37*
G36*
G01X-1261849D02*
X-1261672Y-142335D01*
X-1258379D01*
X-1258202Y-142354D01*
G02X-1258587Y-146536I-223J-2088D01*
G01X-1258597Y-146535D01*
X-1261453D01*
X-1261463Y-146536D01*
G02X-1261849Y-142354I-162J2094D01*
G37*
G36*
G01X-672791Y-146321D02*
Y-148362D01*
X-677291D01*
Y-146315D01*
G02Y-143921I2252J1197D01*
G01Y-140803D01*
G02Y-138410I2252J1197D01*
G01Y-136362D01*
X-672791D01*
Y-138403D01*
G02Y-140810I-2248J-1203D01*
G01Y-143915D01*
G02Y-146321I-2248J-1203D01*
G37*
G36*
G01X-688539D02*
Y-148362D01*
X-693039D01*
Y-146315D01*
G02Y-143921I2252J1197D01*
G01Y-140803D01*
G02Y-138410I2252J1197D01*
G01Y-136362D01*
X-688539D01*
Y-138403D01*
G02Y-140810I-2248J-1203D01*
G01Y-143915D01*
G02Y-146321I-2248J-1203D01*
G37*
G36*
G01X-704287D02*
Y-148362D01*
X-708787D01*
Y-146315D01*
G02Y-143921I2252J1197D01*
G01Y-140803D01*
G02Y-138410I2252J1197D01*
G01Y-136362D01*
X-704287D01*
Y-138403D01*
G02Y-140810I-2248J-1203D01*
G01Y-143915D01*
G02Y-146321I-2248J-1203D01*
G37*
G36*
G01X-720035D02*
Y-148362D01*
X-724535D01*
Y-146315D01*
G02Y-143921I2252J1197D01*
G01Y-140803D01*
G02Y-138410I2252J1197D01*
G01Y-136362D01*
X-720035D01*
Y-138403D01*
G02Y-140810I-2248J-1203D01*
G01Y-143915D01*
G02Y-146321I-2248J-1203D01*
G37*
G36*
G01X-735783D02*
Y-148362D01*
X-740283D01*
Y-146315D01*
G02Y-143921I2252J1197D01*
G01Y-140803D01*
G02Y-138410I2252J1197D01*
G01Y-136362D01*
X-735783D01*
Y-138403D01*
G02Y-140810I-2248J-1203D01*
G01Y-143915D01*
G02Y-146321I-2248J-1203D01*
G37*
G36*
G01X-1542870D02*
Y-148362D01*
X-1547370D01*
Y-146315D01*
G02Y-143921I2252J1197D01*
G01Y-140803D01*
G02Y-138410I2252J1197D01*
G01Y-136362D01*
X-1542870D01*
Y-138403D01*
G02Y-140810I-2248J-1203D01*
G01Y-143915D01*
G02Y-146321I-2248J-1203D01*
G37*
G36*
G01X-1558618D02*
Y-148362D01*
X-1563118D01*
Y-146315D01*
G02Y-143921I2252J1197D01*
G01Y-140803D01*
G02Y-138410I2252J1197D01*
G01Y-136362D01*
X-1558618D01*
Y-138403D01*
G02Y-140810I-2248J-1203D01*
G01Y-143915D01*
G02Y-146321I-2248J-1203D01*
G37*
G36*
G01X-1574366D02*
Y-148362D01*
X-1578866D01*
Y-146315D01*
G02Y-143921I2252J1197D01*
G01Y-140803D01*
G02Y-138410I2252J1197D01*
G01Y-136362D01*
X-1574366D01*
Y-138403D01*
G02Y-140810I-2248J-1203D01*
G01Y-143915D01*
G02Y-146321I-2248J-1203D01*
G37*
G36*
G01X-1590114D02*
Y-148362D01*
X-1594614D01*
Y-146315D01*
G02Y-143921I2252J1197D01*
G01Y-140803D01*
G02Y-138410I2252J1197D01*
G01Y-136362D01*
X-1590114D01*
Y-138403D01*
G02Y-140810I-2248J-1203D01*
G01Y-143915D01*
G02Y-146321I-2248J-1203D01*
G37*
G36*
G01X-1605862D02*
Y-148362D01*
X-1610362D01*
Y-146315D01*
G02Y-143921I2252J1197D01*
G01Y-140803D01*
G02Y-138410I2252J1197D01*
G01Y-136362D01*
X-1605862D01*
Y-138403D01*
G02Y-140810I-2248J-1203D01*
G01Y-143915D01*
G02Y-146321I-2248J-1203D01*
G37*
G36*
G01X-593212Y-146800D02*
X-593211Y-146793D01*
Y-141986D01*
X-593212Y-141979D01*
G02X-590029Y-141674I1598J90D01*
G01X-590011Y-141803D01*
Y-146977D01*
X-590029Y-147106D01*
G02X-593212Y-146800I-1585J216D01*
G37*
G36*
G01X-603212D02*
X-603211Y-146793D01*
Y-141986D01*
X-603212Y-141979D01*
G02X-600029Y-141674I1598J90D01*
G01X-600011Y-141803D01*
Y-146977D01*
X-600029Y-147106D01*
G02X-603212Y-146800I-1585J216D01*
G37*
G36*
G01X-613212D02*
X-613211Y-146793D01*
Y-141986D01*
X-613212Y-141979D01*
G02X-610029Y-141674I1598J90D01*
G01X-610011Y-141803D01*
Y-146977D01*
X-610029Y-147106D01*
G02X-613212Y-146800I-1585J216D01*
G37*
G36*
G01X-1463290D02*
X-1463290Y-146793D01*
Y-141986D01*
X-1463290Y-141979D01*
G02X-1460108Y-141674I1598J90D01*
G01X-1460090Y-141803D01*
Y-146977D01*
X-1460108Y-147106D01*
G02X-1463290Y-146800I-1585J216D01*
G37*
G36*
G01X-1473290D02*
X-1473290Y-146793D01*
Y-141986D01*
X-1473290Y-141979D01*
G02X-1470108Y-141674I1598J90D01*
G01X-1470090Y-141803D01*
Y-146977D01*
X-1470108Y-147106D01*
G02X-1473290Y-146800I-1585J216D01*
G37*
G36*
G01X-1483290D02*
X-1483290Y-146793D01*
Y-141986D01*
X-1483290Y-141979D01*
G02X-1480108Y-141674I1598J90D01*
G01X-1480090Y-141803D01*
Y-146977D01*
X-1480108Y-147106D01*
G02X-1483290Y-146800I-1585J216D01*
G37*
G36*
G01X-102789Y-146712D02*
Y-148756D01*
X-107289D01*
Y-146712D01*
G02Y-144312I2250J1200D01*
G01Y-141200D01*
G02Y-138800I2250J1200D01*
G01Y-136756D01*
X-102789D01*
Y-138800D01*
G02Y-141200I-2250J-1200D01*
G01Y-144312D01*
G02Y-146712I-2250J-1200D01*
G37*
G36*
G01X-118537D02*
Y-148756D01*
X-123037D01*
Y-146712D01*
G02Y-144312I2250J1200D01*
G01Y-141200D01*
G02Y-138800I2250J1200D01*
G01Y-136756D01*
X-118537D01*
Y-138800D01*
G02Y-141200I-2250J-1200D01*
G01Y-144312D01*
G02Y-146712I-2250J-1200D01*
G37*
G36*
G01X-134285D02*
Y-148756D01*
X-138785D01*
Y-146712D01*
G02Y-144312I2250J1200D01*
G01Y-141200D01*
G02Y-138800I2250J1200D01*
G01Y-136756D01*
X-134285D01*
Y-138800D01*
G02Y-141200I-2250J-1200D01*
G01Y-144312D01*
G02Y-146712I-2250J-1200D01*
G37*
G36*
G01X-972868D02*
Y-148756D01*
X-977368D01*
Y-146712D01*
G02Y-144312I2250J1200D01*
G01Y-141200D01*
G02Y-138800I2250J1200D01*
G01Y-136756D01*
X-972868D01*
Y-138800D01*
G02Y-141200I-2250J-1200D01*
G01Y-144312D01*
G02Y-146712I-2250J-1200D01*
G37*
G36*
G01X-988616D02*
Y-148756D01*
X-993116D01*
Y-146712D01*
G02Y-144312I2250J1200D01*
G01Y-141200D01*
G02Y-138800I2250J1200D01*
G01Y-136756D01*
X-988616D01*
Y-138800D01*
G02Y-141200I-2250J-1200D01*
G01Y-144312D01*
G02Y-146712I-2250J-1200D01*
G37*
G36*
G01X-1004364D02*
Y-148756D01*
X-1008864D01*
Y-146712D01*
G02Y-144312I2250J1200D01*
G01Y-141200D01*
G02Y-138800I2250J1200D01*
G01Y-136756D01*
X-1004364D01*
Y-138800D01*
G02Y-141200I-2250J-1200D01*
G01Y-144312D01*
G02Y-146712I-2250J-1200D01*
G37*
G36*
G01X-285311Y-146715D02*
Y-148756D01*
X-289811D01*
Y-146709D01*
G02Y-144315I2252J1197D01*
G01Y-141197D01*
G02Y-138803I2252J1197D01*
G01Y-136756D01*
X-285311D01*
Y-138797D01*
G02Y-141203I-2248J-1203D01*
G01Y-144309D01*
G02Y-146715I-2248J-1203D01*
G37*
G36*
G01X-1155390D02*
Y-148756D01*
X-1159890D01*
Y-146709D01*
G02Y-144315I2252J1197D01*
G01Y-141197D01*
G02Y-138803I2252J1197D01*
G01Y-136756D01*
X-1155390D01*
Y-138797D01*
G02Y-141203I-2248J-1203D01*
G01Y-144309D01*
G02Y-146715I-2248J-1203D01*
G37*
G36*
G01X-353935Y-147819D02*
X-353757Y-147800D01*
X-350465D01*
X-350288Y-147819D01*
G02X-350673Y-152001I-223J-2088D01*
G01X-350683Y-152000D01*
X-353539D01*
X-353548Y-152001D01*
G02X-353935Y-147819I-162J2094D01*
G37*
G36*
G01X-1224013D02*
X-1223836Y-147800D01*
X-1220543D01*
X-1220366Y-147819D01*
G02X-1220752Y-152001I-223J-2088D01*
G01X-1220762Y-152000D01*
X-1223617D01*
X-1223627Y-152001D01*
G02X-1224013Y-147819I-162J2094D01*
G37*
G36*
G01X-401233Y-149699D02*
X-401056Y-149680D01*
X-397763D01*
X-397586Y-149699D01*
G02X-397971Y-153881I-223J-2088D01*
G01X-397981Y-153880D01*
X-400837D01*
X-400847Y-153881D01*
G02X-401233Y-149699I-162J2094D01*
G37*
G36*
G01X-1271312D02*
X-1271134Y-149680D01*
X-1267842D01*
X-1267665Y-149699D01*
G02X-1268050Y-153881I-223J-2088D01*
G01X-1268060Y-153880D01*
X-1270916D01*
X-1270925Y-153881D01*
G02X-1271312Y-149699I-162J2094D01*
G37*
G36*
G01X-253595Y-153102D02*
X-253418Y-153083D01*
X-250125D01*
X-249948Y-153102D01*
G02X-250334Y-157284I-223J-2088D01*
G01X-250343Y-157283D01*
X-253199D01*
X-253209Y-157284D01*
G02X-253595Y-153102I-162J2094D01*
G37*
G36*
G01X-1123674D02*
X-1123497Y-153083D01*
X-1120204D01*
X-1120027Y-153102D01*
G02X-1120412Y-157284I-223J-2088D01*
G01X-1120422Y-157283D01*
X-1123278D01*
X-1123288Y-157284D01*
G02X-1123674Y-153102I-162J2094D01*
G37*
G36*
G01X-598212Y-156800D02*
X-598211Y-156793D01*
Y-151986D01*
X-598212Y-151979D01*
G02X-595029Y-151674I1598J90D01*
G01X-595011Y-151803D01*
Y-156977D01*
X-595029Y-157106D01*
G02X-598212Y-156800I-1585J216D01*
G37*
G36*
G01X-608212D02*
X-608211Y-156793D01*
Y-151986D01*
X-608212Y-151979D01*
G02X-605029Y-151674I1598J90D01*
G01X-605011Y-151803D01*
Y-156977D01*
X-605029Y-157106D01*
G02X-608212Y-156800I-1585J216D01*
G37*
G36*
G01X-618212D02*
X-618211Y-156793D01*
Y-151986D01*
X-618212Y-151979D01*
G02X-615029Y-151674I1598J90D01*
G01X-615011Y-151803D01*
Y-156977D01*
X-615029Y-157106D01*
G02X-618212Y-156800I-1585J216D01*
G37*
G36*
G01X-1468290D02*
X-1468290Y-156793D01*
Y-151986D01*
X-1468290Y-151979D01*
G02X-1465108Y-151674I1598J90D01*
G01X-1465090Y-151803D01*
Y-156977D01*
X-1465108Y-157106D01*
G02X-1468290Y-156800I-1585J216D01*
G37*
G36*
G01X-1478290D02*
X-1478290Y-156793D01*
Y-151986D01*
X-1478290Y-151979D01*
G02X-1475108Y-151674I1598J90D01*
G01X-1475090Y-151803D01*
Y-156977D01*
X-1475108Y-157106D01*
G02X-1478290Y-156800I-1585J216D01*
G37*
G36*
G01X-1488290D02*
X-1488290Y-156793D01*
Y-151986D01*
X-1488290Y-151979D01*
G02X-1485108Y-151674I1598J90D01*
G01X-1485090Y-151803D01*
Y-156977D01*
X-1485108Y-157106D01*
G02X-1488290Y-156800I-1585J216D01*
G37*
G36*
G01X-680665Y-157739D02*
Y-159780D01*
X-685165D01*
Y-157732D01*
G02Y-155339I2252J1197D01*
G01Y-152220D01*
G02Y-149827I2252J1197D01*
G01Y-147780D01*
X-680665D01*
Y-149820D01*
G02Y-152227I-2248J-1203D01*
G01Y-155332D01*
G02Y-157739I-2248J-1203D01*
G37*
G36*
G01X-696413D02*
Y-159780D01*
X-700913D01*
Y-157732D01*
G02Y-155339I2252J1197D01*
G01Y-152220D01*
G02Y-149827I2252J1197D01*
G01Y-147780D01*
X-696413D01*
Y-149820D01*
G02Y-152227I-2248J-1203D01*
G01Y-155332D01*
G02Y-157739I-2248J-1203D01*
G37*
G36*
G01X-712161D02*
Y-159780D01*
X-716661D01*
Y-157732D01*
G02Y-155339I2252J1197D01*
G01Y-152220D01*
G02Y-149827I2252J1197D01*
G01Y-147780D01*
X-712161D01*
Y-149820D01*
G02Y-152227I-2248J-1203D01*
G01Y-155332D01*
G02Y-157739I-2248J-1203D01*
G37*
G36*
G01X-727909D02*
Y-159780D01*
X-732409D01*
Y-157732D01*
G02Y-155339I2252J1197D01*
G01Y-152220D01*
G02Y-149827I2252J1197D01*
G01Y-147780D01*
X-727909D01*
Y-149820D01*
G02Y-152227I-2248J-1203D01*
G01Y-155332D01*
G02Y-157739I-2248J-1203D01*
G37*
G36*
G01X-1550744D02*
Y-159780D01*
X-1555244D01*
Y-157732D01*
G02Y-155339I2252J1197D01*
G01Y-152220D01*
G02Y-149827I2252J1197D01*
G01Y-147780D01*
X-1550744D01*
Y-149820D01*
G02Y-152227I-2248J-1203D01*
G01Y-155332D01*
G02Y-157739I-2248J-1203D01*
G37*
G36*
G01X-1566492D02*
Y-159780D01*
X-1570992D01*
Y-157732D01*
G02Y-155339I2252J1197D01*
G01Y-152220D01*
G02Y-149827I2252J1197D01*
G01Y-147780D01*
X-1566492D01*
Y-149820D01*
G02Y-152227I-2248J-1203D01*
G01Y-155332D01*
G02Y-157739I-2248J-1203D01*
G37*
G36*
G01X-1582240D02*
Y-159780D01*
X-1586740D01*
Y-157732D01*
G02Y-155339I2252J1197D01*
G01Y-152220D01*
G02Y-149827I2252J1197D01*
G01Y-147780D01*
X-1582240D01*
Y-149820D01*
G02Y-152227I-2248J-1203D01*
G01Y-155332D01*
G02Y-157739I-2248J-1203D01*
G37*
G36*
G01X-1597988D02*
Y-159780D01*
X-1602488D01*
Y-157732D01*
G02Y-155339I2252J1197D01*
G01Y-152220D01*
G02Y-149827I2252J1197D01*
G01Y-147780D01*
X-1597988D01*
Y-149820D01*
G02Y-152227I-2248J-1203D01*
G01Y-155332D01*
G02Y-157739I-2248J-1203D01*
G37*
G36*
G01X-324681Y-158132D02*
Y-160173D01*
X-329181D01*
Y-158126D01*
G02Y-155732I2252J1197D01*
G01Y-152614D01*
G02Y-150221I2252J1197D01*
G01Y-148173D01*
X-324681D01*
Y-150214D01*
G02Y-152621I-2248J-1203D01*
G01Y-155726D01*
G02Y-158132I-2248J-1203D01*
G37*
G36*
G01X-1194760D02*
Y-160173D01*
X-1199260D01*
Y-158126D01*
G02Y-155732I2252J1197D01*
G01Y-152614D01*
G02Y-150221I2252J1197D01*
G01Y-148173D01*
X-1194760D01*
Y-150214D01*
G02Y-152621I-2248J-1203D01*
G01Y-155726D01*
G02Y-158132I-2248J-1203D01*
G37*
G36*
G01X-110663Y-158129D02*
Y-160173D01*
X-115163D01*
Y-158129D01*
G02Y-155729I2250J1200D01*
G01Y-152617D01*
G02Y-150217I2250J1200D01*
G01Y-148173D01*
X-110663D01*
Y-150217D01*
G02Y-152617I-2250J-1200D01*
G01Y-155729D01*
G02Y-158129I-2250J-1200D01*
G37*
G36*
G01X-126411D02*
Y-160173D01*
X-130911D01*
Y-158129D01*
G02Y-155729I2250J1200D01*
G01Y-152617D01*
G02Y-150217I2250J1200D01*
G01Y-148173D01*
X-126411D01*
Y-150217D01*
G02Y-152617I-2250J-1200D01*
G01Y-155729D01*
G02Y-158129I-2250J-1200D01*
G37*
G36*
G01X-142159D02*
Y-160173D01*
X-146659D01*
Y-158129D01*
G02Y-155729I2250J1200D01*
G01Y-152617D01*
G02Y-150217I2250J1200D01*
G01Y-148173D01*
X-142159D01*
Y-150217D01*
G02Y-152617I-2250J-1200D01*
G01Y-155729D01*
G02Y-158129I-2250J-1200D01*
G37*
G36*
G01X-980742D02*
Y-160173D01*
X-985242D01*
Y-158129D01*
G02Y-155729I2250J1200D01*
G01Y-152617D01*
G02Y-150217I2250J1200D01*
G01Y-148173D01*
X-980742D01*
Y-150217D01*
G02Y-152617I-2250J-1200D01*
G01Y-155729D01*
G02Y-158129I-2250J-1200D01*
G37*
G36*
G01X-996490D02*
Y-160173D01*
X-1000990D01*
Y-158129D01*
G02Y-155729I2250J1200D01*
G01Y-152617D01*
G02Y-150217I2250J1200D01*
G01Y-148173D01*
X-996490D01*
Y-150217D01*
G02Y-152617I-2250J-1200D01*
G01Y-155729D01*
G02Y-158129I-2250J-1200D01*
G37*
G36*
G01X-1012238D02*
Y-160173D01*
X-1016738D01*
Y-158129D01*
G02Y-155729I2250J1200D01*
G01Y-152617D01*
G02Y-150217I2250J1200D01*
G01Y-148173D01*
X-1012238D01*
Y-150217D01*
G02Y-152617I-2250J-1200D01*
G01Y-155729D01*
G02Y-158129I-2250J-1200D01*
G37*
G36*
G01X-672791Y-162857D02*
Y-164898D01*
X-677291D01*
Y-162850D01*
G02Y-160457I2252J1197D01*
G01Y-157339D01*
G02Y-154945I2252J1197D01*
G01Y-152898D01*
X-672791D01*
Y-154939D01*
G02Y-157345I-2248J-1203D01*
G01Y-160450D01*
G02Y-162857I-2248J-1203D01*
G37*
G36*
G01X-688539D02*
Y-164898D01*
X-693039D01*
Y-162850D01*
G02Y-160457I2252J1197D01*
G01Y-157339D01*
G02Y-154945I2252J1197D01*
G01Y-152898D01*
X-688539D01*
Y-154939D01*
G02Y-157345I-2248J-1203D01*
G01Y-160450D01*
G02Y-162857I-2248J-1203D01*
G37*
G36*
G01X-704287D02*
Y-164898D01*
X-708787D01*
Y-162850D01*
G02Y-160457I2252J1197D01*
G01Y-157339D01*
G02Y-154945I2252J1197D01*
G01Y-152898D01*
X-704287D01*
Y-154939D01*
G02Y-157345I-2248J-1203D01*
G01Y-160450D01*
G02Y-162857I-2248J-1203D01*
G37*
G36*
G01X-720035D02*
Y-164898D01*
X-724535D01*
Y-162850D01*
G02Y-160457I2252J1197D01*
G01Y-157339D01*
G02Y-154945I2252J1197D01*
G01Y-152898D01*
X-720035D01*
Y-154939D01*
G02Y-157345I-2248J-1203D01*
G01Y-160450D01*
G02Y-162857I-2248J-1203D01*
G37*
G36*
G01X-735783D02*
Y-164898D01*
X-740283D01*
Y-162850D01*
G02Y-160457I2252J1197D01*
G01Y-157339D01*
G02Y-154945I2252J1197D01*
G01Y-152898D01*
X-735783D01*
Y-154939D01*
G02Y-157345I-2248J-1203D01*
G01Y-160450D01*
G02Y-162857I-2248J-1203D01*
G37*
G36*
G01X-1542870D02*
Y-164898D01*
X-1547370D01*
Y-162850D01*
G02Y-160457I2252J1197D01*
G01Y-157339D01*
G02Y-154945I2252J1197D01*
G01Y-152898D01*
X-1542870D01*
Y-154939D01*
G02Y-157345I-2248J-1203D01*
G01Y-160450D01*
G02Y-162857I-2248J-1203D01*
G37*
G36*
G01X-1558618D02*
Y-164898D01*
X-1563118D01*
Y-162850D01*
G02Y-160457I2252J1197D01*
G01Y-157339D01*
G02Y-154945I2252J1197D01*
G01Y-152898D01*
X-1558618D01*
Y-154939D01*
G02Y-157345I-2248J-1203D01*
G01Y-160450D01*
G02Y-162857I-2248J-1203D01*
G37*
G36*
G01X-1574366D02*
Y-164898D01*
X-1578866D01*
Y-162850D01*
G02Y-160457I2252J1197D01*
G01Y-157339D01*
G02Y-154945I2252J1197D01*
G01Y-152898D01*
X-1574366D01*
Y-154939D01*
G02Y-157345I-2248J-1203D01*
G01Y-160450D01*
G02Y-162857I-2248J-1203D01*
G37*
G36*
G01X-1590114D02*
Y-164898D01*
X-1594614D01*
Y-162850D01*
G02Y-160457I2252J1197D01*
G01Y-157339D01*
G02Y-154945I2252J1197D01*
G01Y-152898D01*
X-1590114D01*
Y-154939D01*
G02Y-157345I-2248J-1203D01*
G01Y-160450D01*
G02Y-162857I-2248J-1203D01*
G37*
G36*
G01X-1605862D02*
Y-164898D01*
X-1610362D01*
Y-162850D01*
G02Y-160457I2252J1197D01*
G01Y-157339D01*
G02Y-154945I2252J1197D01*
G01Y-152898D01*
X-1605862D01*
Y-154939D01*
G02Y-157345I-2248J-1203D01*
G01Y-160450D01*
G02Y-162857I-2248J-1203D01*
G37*
G36*
G01X-102789Y-163247D02*
Y-165291D01*
X-107289D01*
Y-163247D01*
G02Y-160847I2250J1200D01*
G01Y-157735D01*
G02Y-155335I2250J1200D01*
G01Y-153291D01*
X-102789D01*
Y-155335D01*
G02Y-157735I-2250J-1200D01*
G01Y-160847D01*
G02Y-163247I-2250J-1200D01*
G37*
G36*
G01X-118537D02*
Y-165291D01*
X-123037D01*
Y-163247D01*
G02Y-160847I2250J1200D01*
G01Y-157735D01*
G02Y-155335I2250J1200D01*
G01Y-153291D01*
X-118537D01*
Y-155335D01*
G02Y-157735I-2250J-1200D01*
G01Y-160847D01*
G02Y-163247I-2250J-1200D01*
G37*
G36*
G01X-134285D02*
Y-165291D01*
X-138785D01*
Y-163247D01*
G02Y-160847I2250J1200D01*
G01Y-157735D01*
G02Y-155335I2250J1200D01*
G01Y-153291D01*
X-134285D01*
Y-155335D01*
G02Y-157735I-2250J-1200D01*
G01Y-160847D01*
G02Y-163247I-2250J-1200D01*
G37*
G36*
G01X-972868D02*
Y-165291D01*
X-977368D01*
Y-163247D01*
G02Y-160847I2250J1200D01*
G01Y-157735D01*
G02Y-155335I2250J1200D01*
G01Y-153291D01*
X-972868D01*
Y-155335D01*
G02Y-157735I-2250J-1200D01*
G01Y-160847D01*
G02Y-163247I-2250J-1200D01*
G37*
G36*
G01X-988616D02*
Y-165291D01*
X-993116D01*
Y-163247D01*
G02Y-160847I2250J1200D01*
G01Y-157735D01*
G02Y-155335I2250J1200D01*
G01Y-153291D01*
X-988616D01*
Y-155335D01*
G02Y-157735I-2250J-1200D01*
G01Y-160847D01*
G02Y-163247I-2250J-1200D01*
G37*
G36*
G01X-1004364D02*
Y-165291D01*
X-1008864D01*
Y-163247D01*
G02Y-160847I2250J1200D01*
G01Y-157735D01*
G02Y-155335I2250J1200D01*
G01Y-153291D01*
X-1004364D01*
Y-155335D01*
G02Y-157735I-2250J-1200D01*
G01Y-160847D01*
G02Y-163247I-2250J-1200D01*
G37*
G36*
G01X-285311Y-163250D02*
Y-165291D01*
X-289811D01*
Y-163244D01*
G02Y-160850I2252J1197D01*
G01Y-157732D01*
G02Y-155339I2252J1197D01*
G01Y-153291D01*
X-285311D01*
Y-155332D01*
G02Y-157739I-2248J-1203D01*
G01Y-160844D01*
G02Y-163250I-2248J-1203D01*
G37*
G36*
G01X-1155390D02*
Y-165291D01*
X-1159890D01*
Y-163244D01*
G02Y-160850I2252J1197D01*
G01Y-157732D01*
G02Y-155339I2252J1197D01*
G01Y-153291D01*
X-1155390D01*
Y-155332D01*
G02Y-157739I-2248J-1203D01*
G01Y-160844D01*
G02Y-163250I-2248J-1203D01*
G37*
G36*
G01X-593212Y-166800D02*
X-593211Y-166793D01*
Y-161986D01*
X-593212Y-161979D01*
G02X-590029Y-161674I1598J90D01*
G01X-590011Y-161803D01*
Y-166977D01*
X-590029Y-167106D01*
G02X-593212Y-166800I-1585J216D01*
G37*
G36*
G01X-603212D02*
X-603211Y-166793D01*
Y-161986D01*
X-603212Y-161979D01*
G02X-600029Y-161674I1598J90D01*
G01X-600011Y-161803D01*
Y-166977D01*
X-600029Y-167106D01*
G02X-603212Y-166800I-1585J216D01*
G37*
G36*
G01X-613212D02*
X-613211Y-166793D01*
Y-161986D01*
X-613212Y-161979D01*
G02X-610029Y-161674I1598J90D01*
G01X-610011Y-161803D01*
Y-166977D01*
X-610029Y-167106D01*
G02X-613212Y-166800I-1585J216D01*
G37*
G36*
G01X-1463290D02*
X-1463290Y-166793D01*
Y-161986D01*
X-1463290Y-161979D01*
G02X-1460108Y-161674I1598J90D01*
G01X-1460090Y-161803D01*
Y-166977D01*
X-1460108Y-167106D01*
G02X-1463290Y-166800I-1585J216D01*
G37*
G36*
G01X-1473290D02*
X-1473290Y-166793D01*
Y-161986D01*
X-1473290Y-161979D01*
G02X-1470108Y-161674I1598J90D01*
G01X-1470090Y-161803D01*
Y-166977D01*
X-1470108Y-167106D01*
G02X-1473290Y-166800I-1585J216D01*
G37*
G36*
G01X-1483290D02*
X-1483290Y-166793D01*
Y-161986D01*
X-1483290Y-161979D01*
G02X-1480108Y-161674I1598J90D01*
G01X-1480090Y-161803D01*
Y-166977D01*
X-1480108Y-167106D01*
G02X-1483290Y-166800I-1585J216D01*
G37*
G36*
G01X-339565Y-165279D02*
X-339388Y-165260D01*
X-336095D01*
X-335918Y-165279D01*
G02X-336303Y-169461I-223J-2088D01*
G01X-336313Y-169460D01*
X-339169D01*
X-339178Y-169461D01*
G02X-339565Y-165279I-162J2094D01*
G37*
G36*
G01X-1209643D02*
X-1209466Y-165260D01*
X-1206173D01*
X-1205997Y-165279D01*
G02X-1206382Y-169461I-223J-2088D01*
G01X-1206392Y-169460D01*
X-1209248D01*
X-1209257Y-169461D01*
G02X-1209643Y-165279I-162J2094D01*
G37*
G36*
G01X-680665Y-174274D02*
Y-176315D01*
X-685165D01*
Y-174268D01*
G02Y-171874I2252J1197D01*
G01Y-168756D01*
G02Y-166362I2252J1197D01*
G01Y-164315D01*
X-680665D01*
Y-166356D01*
G02Y-168762I-2248J-1203D01*
G01Y-171868D01*
G02Y-174274I-2248J-1203D01*
G37*
G36*
G01X-696413D02*
Y-176315D01*
X-700913D01*
Y-174268D01*
G02Y-171874I2252J1197D01*
G01Y-168756D01*
G02Y-166362I2252J1197D01*
G01Y-164315D01*
X-696413D01*
Y-166356D01*
G02Y-168762I-2248J-1203D01*
G01Y-171868D01*
G02Y-174274I-2248J-1203D01*
G37*
G36*
G01X-712161D02*
Y-176315D01*
X-716661D01*
Y-174268D01*
G02Y-171874I2252J1197D01*
G01Y-168756D01*
G02Y-166362I2252J1197D01*
G01Y-164315D01*
X-712161D01*
Y-166356D01*
G02Y-168762I-2248J-1203D01*
G01Y-171868D01*
G02Y-174274I-2248J-1203D01*
G37*
G36*
G01X-727909D02*
Y-176315D01*
X-732409D01*
Y-174268D01*
G02Y-171874I2252J1197D01*
G01Y-168756D01*
G02Y-166362I2252J1197D01*
G01Y-164315D01*
X-727909D01*
Y-166356D01*
G02Y-168762I-2248J-1203D01*
G01Y-171868D01*
G02Y-174274I-2248J-1203D01*
G37*
G36*
G01X-743657D02*
Y-176315D01*
X-748157D01*
Y-174268D01*
G02Y-171874I2252J1197D01*
G01Y-168756D01*
G02Y-166362I2252J1197D01*
G01Y-164315D01*
X-743657D01*
Y-166356D01*
G02Y-168762I-2248J-1203D01*
G01Y-171868D01*
G02Y-174274I-2248J-1203D01*
G37*
G36*
G01X-1550744D02*
Y-176315D01*
X-1555244D01*
Y-174268D01*
G02Y-171874I2252J1197D01*
G01Y-168756D01*
G02Y-166362I2252J1197D01*
G01Y-164315D01*
X-1550744D01*
Y-166356D01*
G02Y-168762I-2248J-1203D01*
G01Y-171868D01*
G02Y-174274I-2248J-1203D01*
G37*
G36*
G01X-1566492D02*
Y-176315D01*
X-1570992D01*
Y-174268D01*
G02Y-171874I2252J1197D01*
G01Y-168756D01*
G02Y-166362I2252J1197D01*
G01Y-164315D01*
X-1566492D01*
Y-166356D01*
G02Y-168762I-2248J-1203D01*
G01Y-171868D01*
G02Y-174274I-2248J-1203D01*
G37*
G36*
G01X-1582240D02*
Y-176315D01*
X-1586740D01*
Y-174268D01*
G02Y-171874I2252J1197D01*
G01Y-168756D01*
G02Y-166362I2252J1197D01*
G01Y-164315D01*
X-1582240D01*
Y-166356D01*
G02Y-168762I-2248J-1203D01*
G01Y-171868D01*
G02Y-174274I-2248J-1203D01*
G37*
G36*
G01X-1597988D02*
Y-176315D01*
X-1602488D01*
Y-174268D01*
G02Y-171874I2252J1197D01*
G01Y-168756D01*
G02Y-166362I2252J1197D01*
G01Y-164315D01*
X-1597988D01*
Y-166356D01*
G02Y-168762I-2248J-1203D01*
G01Y-171868D01*
G02Y-174274I-2248J-1203D01*
G37*
G36*
G01X-1613736D02*
Y-176315D01*
X-1618236D01*
Y-174268D01*
G02Y-171874I2252J1197D01*
G01Y-168756D01*
G02Y-166362I2252J1197D01*
G01Y-164315D01*
X-1613736D01*
Y-166356D01*
G02Y-168762I-2248J-1203D01*
G01Y-171868D01*
G02Y-174274I-2248J-1203D01*
G37*
G36*
G01X-1347998Y-164437D02*
G02Y-169894I-8891J-2729D01*
G02Y-164437I-8891J2729D01*
G37*
G36*
G01X-110663Y-174665D02*
Y-176709D01*
X-115163D01*
Y-174665D01*
G02Y-172265I2250J1200D01*
G01Y-169153D01*
G02Y-166753I2250J1200D01*
G01Y-164709D01*
X-110663D01*
Y-166753D01*
G02Y-169153I-2250J-1200D01*
G01Y-172265D01*
G02Y-174665I-2250J-1200D01*
G37*
G36*
G01X-142159D02*
Y-176709D01*
X-146659D01*
Y-174665D01*
G02Y-172265I2250J1200D01*
G01Y-169153D01*
G02Y-166753I2250J1200D01*
G01Y-164709D01*
X-142159D01*
Y-166753D01*
G02Y-169153I-2250J-1200D01*
G01Y-172265D01*
G02Y-174665I-2250J-1200D01*
G37*
G36*
G01X-980742D02*
Y-176709D01*
X-985242D01*
Y-174665D01*
G02Y-172265I2250J1200D01*
G01Y-169153D01*
G02Y-166753I2250J1200D01*
G01Y-164709D01*
X-980742D01*
Y-166753D01*
G02Y-169153I-2250J-1200D01*
G01Y-172265D01*
G02Y-174665I-2250J-1200D01*
G37*
G36*
G01X-1012238D02*
Y-176709D01*
X-1016738D01*
Y-174665D01*
G02Y-172265I2250J1200D01*
G01Y-169153D01*
G02Y-166753I2250J1200D01*
G01Y-164709D01*
X-1012238D01*
Y-166753D01*
G02Y-169153I-2250J-1200D01*
G01Y-172265D01*
G02Y-174665I-2250J-1200D01*
G37*
G36*
G01X-293185Y-174668D02*
Y-176709D01*
X-297685D01*
Y-174661D01*
G02Y-172268I2252J1197D01*
G01Y-169150D01*
G02Y-166756I2252J1197D01*
G01Y-164709D01*
X-293185D01*
Y-166750D01*
G02Y-169156I-2248J-1203D01*
G01Y-172261D01*
G02Y-174668I-2248J-1203D01*
G37*
G36*
G01X-308933D02*
Y-176709D01*
X-313433D01*
Y-174661D01*
G02Y-172268I2252J1197D01*
G01Y-169150D01*
G02Y-166756I2252J1197D01*
G01Y-164709D01*
X-308933D01*
Y-166750D01*
G02Y-169156I-2248J-1203D01*
G01Y-172261D01*
G02Y-174668I-2248J-1203D01*
G37*
G36*
G01X-324681D02*
Y-176709D01*
X-329181D01*
Y-174661D01*
G02Y-172268I2252J1197D01*
G01Y-169150D01*
G02Y-166756I2252J1197D01*
G01Y-164709D01*
X-324681D01*
Y-166750D01*
G02Y-169156I-2248J-1203D01*
G01Y-172261D01*
G02Y-174668I-2248J-1203D01*
G37*
G36*
G01X-1163264D02*
Y-176709D01*
X-1167764D01*
Y-174661D01*
G02Y-172268I2252J1197D01*
G01Y-169150D01*
G02Y-166756I2252J1197D01*
G01Y-164709D01*
X-1163264D01*
Y-166750D01*
G02Y-169156I-2248J-1203D01*
G01Y-172261D01*
G02Y-174668I-2248J-1203D01*
G37*
G36*
G01X-1179012D02*
Y-176709D01*
X-1183512D01*
Y-174661D01*
G02Y-172268I2252J1197D01*
G01Y-169150D01*
G02Y-166756I2252J1197D01*
G01Y-164709D01*
X-1179012D01*
Y-166750D01*
G02Y-169156I-2248J-1203D01*
G01Y-172261D01*
G02Y-174668I-2248J-1203D01*
G37*
G36*
G01X-1194760D02*
Y-176709D01*
X-1199260D01*
Y-174661D01*
G02Y-172268I2252J1197D01*
G01Y-169150D01*
G02Y-166756I2252J1197D01*
G01Y-164709D01*
X-1194760D01*
Y-166750D01*
G02Y-169156I-2248J-1203D01*
G01Y-172261D01*
G02Y-174668I-2248J-1203D01*
G37*
G36*
G01X-672791Y-179392D02*
Y-181433D01*
X-677291D01*
Y-179386D01*
G02Y-176992I2252J1197D01*
G01Y-173874D01*
G02Y-171480I2252J1197D01*
G01Y-169433D01*
X-672791D01*
Y-171474D01*
G02Y-173880I-2248J-1203D01*
G01Y-176986D01*
G02Y-179392I-2248J-1203D01*
G37*
G36*
G01X-688539D02*
Y-181433D01*
X-693039D01*
Y-179386D01*
G02Y-176992I2252J1197D01*
G01Y-173874D01*
G02Y-171480I2252J1197D01*
G01Y-169433D01*
X-688539D01*
Y-171474D01*
G02Y-173880I-2248J-1203D01*
G01Y-176986D01*
G02Y-179392I-2248J-1203D01*
G37*
G36*
G01X-704287D02*
Y-181433D01*
X-708787D01*
Y-179386D01*
G02Y-176992I2252J1197D01*
G01Y-173874D01*
G02Y-171480I2252J1197D01*
G01Y-169433D01*
X-704287D01*
Y-171474D01*
G02Y-173880I-2248J-1203D01*
G01Y-176986D01*
G02Y-179392I-2248J-1203D01*
G37*
G36*
G01X-720035D02*
Y-181433D01*
X-724535D01*
Y-179386D01*
G02Y-176992I2252J1197D01*
G01Y-173874D01*
G02Y-171480I2252J1197D01*
G01Y-169433D01*
X-720035D01*
Y-171474D01*
G02Y-173880I-2248J-1203D01*
G01Y-176986D01*
G02Y-179392I-2248J-1203D01*
G37*
G36*
G01X-735783D02*
Y-181433D01*
X-740283D01*
Y-179386D01*
G02Y-176992I2252J1197D01*
G01Y-173874D01*
G02Y-171480I2252J1197D01*
G01Y-169433D01*
X-735783D01*
Y-171474D01*
G02Y-173880I-2248J-1203D01*
G01Y-176986D01*
G02Y-179392I-2248J-1203D01*
G37*
G36*
G01X-1542870D02*
Y-181433D01*
X-1547370D01*
Y-179386D01*
G02Y-176992I2252J1197D01*
G01Y-173874D01*
G02Y-171480I2252J1197D01*
G01Y-169433D01*
X-1542870D01*
Y-171474D01*
G02Y-173880I-2248J-1203D01*
G01Y-176986D01*
G02Y-179392I-2248J-1203D01*
G37*
G36*
G01X-1558618D02*
Y-181433D01*
X-1563118D01*
Y-179386D01*
G02Y-176992I2252J1197D01*
G01Y-173874D01*
G02Y-171480I2252J1197D01*
G01Y-169433D01*
X-1558618D01*
Y-171474D01*
G02Y-173880I-2248J-1203D01*
G01Y-176986D01*
G02Y-179392I-2248J-1203D01*
G37*
G36*
G01X-1574366D02*
Y-181433D01*
X-1578866D01*
Y-179386D01*
G02Y-176992I2252J1197D01*
G01Y-173874D01*
G02Y-171480I2252J1197D01*
G01Y-169433D01*
X-1574366D01*
Y-171474D01*
G02Y-173880I-2248J-1203D01*
G01Y-176986D01*
G02Y-179392I-2248J-1203D01*
G37*
G36*
G01X-1590114D02*
Y-181433D01*
X-1594614D01*
Y-179386D01*
G02Y-176992I2252J1197D01*
G01Y-173874D01*
G02Y-171480I2252J1197D01*
G01Y-169433D01*
X-1590114D01*
Y-171474D01*
G02Y-173880I-2248J-1203D01*
G01Y-176986D01*
G02Y-179392I-2248J-1203D01*
G37*
G36*
G01X-1605862D02*
Y-181433D01*
X-1610362D01*
Y-179386D01*
G02Y-176992I2252J1197D01*
G01Y-173874D01*
G02Y-171480I2252J1197D01*
G01Y-169433D01*
X-1605862D01*
Y-171474D01*
G02Y-173880I-2248J-1203D01*
G01Y-176986D01*
G02Y-179392I-2248J-1203D01*
G37*
G36*
G01X-102789Y-179783D02*
Y-181827D01*
X-107289D01*
Y-179783D01*
G02Y-177383I2250J1200D01*
G01Y-174271D01*
G02Y-171871I2250J1200D01*
G01Y-169827D01*
X-102789D01*
Y-171871D01*
G02Y-174271I-2250J-1200D01*
G01Y-177383D01*
G02Y-179783I-2250J-1200D01*
G37*
G36*
G01X-134285D02*
Y-181827D01*
X-138785D01*
Y-179783D01*
G02Y-177383I2250J1200D01*
G01Y-174271D01*
G02Y-171871I2250J1200D01*
G01Y-169827D01*
X-134285D01*
Y-171871D01*
G02Y-174271I-2250J-1200D01*
G01Y-177383D01*
G02Y-179783I-2250J-1200D01*
G37*
G36*
G01X-972868D02*
Y-181827D01*
X-977368D01*
Y-179783D01*
G02Y-177383I2250J1200D01*
G01Y-174271D01*
G02Y-171871I2250J1200D01*
G01Y-169827D01*
X-972868D01*
Y-171871D01*
G02Y-174271I-2250J-1200D01*
G01Y-177383D01*
G02Y-179783I-2250J-1200D01*
G37*
G36*
G01X-1004364D02*
Y-181827D01*
X-1008864D01*
Y-179783D01*
G02Y-177383I2250J1200D01*
G01Y-174271D01*
G02Y-171871I2250J1200D01*
G01Y-169827D01*
X-1004364D01*
Y-171871D01*
G02Y-174271I-2250J-1200D01*
G01Y-177383D01*
G02Y-179783I-2250J-1200D01*
G37*
G36*
G01X-285311Y-179786D02*
Y-181827D01*
X-289811D01*
Y-179779D01*
G02Y-177386I2252J1197D01*
G01Y-174268D01*
G02Y-171874I2252J1197D01*
G01Y-169827D01*
X-285311D01*
Y-171868D01*
G02Y-174274I-2248J-1203D01*
G01Y-177379D01*
G02Y-179786I-2248J-1203D01*
G37*
G36*
G01X-301059D02*
Y-181827D01*
X-305559D01*
Y-179779D01*
G02Y-177386I2252J1197D01*
G01Y-174268D01*
G02Y-171874I2252J1197D01*
G01Y-169827D01*
X-301059D01*
Y-171868D01*
G02Y-174274I-2248J-1203D01*
G01Y-177379D01*
G02Y-179786I-2248J-1203D01*
G37*
G36*
G01X-316807D02*
Y-181827D01*
X-321307D01*
Y-179779D01*
G02Y-177386I2252J1197D01*
G01Y-174268D01*
G02Y-171874I2252J1197D01*
G01Y-169827D01*
X-316807D01*
Y-171868D01*
G02Y-174274I-2248J-1203D01*
G01Y-177379D01*
G02Y-179786I-2248J-1203D01*
G37*
G36*
G01X-1155390D02*
Y-181827D01*
X-1159890D01*
Y-179779D01*
G02Y-177386I2252J1197D01*
G01Y-174268D01*
G02Y-171874I2252J1197D01*
G01Y-169827D01*
X-1155390D01*
Y-171868D01*
G02Y-174274I-2248J-1203D01*
G01Y-177379D01*
G02Y-179786I-2248J-1203D01*
G37*
G36*
G01X-1171138D02*
Y-181827D01*
X-1175638D01*
Y-179779D01*
G02Y-177386I2252J1197D01*
G01Y-174268D01*
G02Y-171874I2252J1197D01*
G01Y-169827D01*
X-1171138D01*
Y-171868D01*
G02Y-174274I-2248J-1203D01*
G01Y-177379D01*
G02Y-179786I-2248J-1203D01*
G37*
G36*
G01X-1186886D02*
Y-181827D01*
X-1191386D01*
Y-179779D01*
G02Y-177386I2252J1197D01*
G01Y-174268D01*
G02Y-171874I2252J1197D01*
G01Y-169827D01*
X-1186886D01*
Y-171868D01*
G02Y-174274I-2248J-1203D01*
G01Y-177379D01*
G02Y-179786I-2248J-1203D01*
G37*
G36*
G01X-399658Y-181556D02*
X-399481Y-181537D01*
X-396188D01*
X-396011Y-181556D01*
G02X-396397Y-185738I-223J-2088D01*
G01X-396406Y-185737D01*
X-399262D01*
X-399272Y-185738D01*
G02X-399658Y-181556I-162J2094D01*
G37*
G36*
G01X-1269737D02*
X-1269560Y-181537D01*
X-1266267D01*
X-1266090Y-181556D01*
G02X-1266475Y-185738I-223J-2088D01*
G01X-1266485Y-185737D01*
X-1269341D01*
X-1269351Y-185738D01*
G02X-1269737Y-181556I-162J2094D01*
G37*
G36*
G01X-365685Y-183299D02*
X-365508Y-183280D01*
X-362215D01*
X-362038Y-183299D01*
G02X-362423Y-187481I-223J-2088D01*
G01X-362433Y-187480D01*
X-365289D01*
X-365298Y-187481D01*
G02X-365685Y-183299I-162J2094D01*
G37*
G36*
G01X-1235763D02*
X-1235586Y-183280D01*
X-1232293D01*
X-1232117Y-183299D01*
G02X-1232502Y-187481I-223J-2088D01*
G01X-1232512Y-187480D01*
X-1235368D01*
X-1235377Y-187481D01*
G02X-1235763Y-183299I-162J2094D01*
G37*
G36*
G01X-377732Y-190129D02*
X-377751Y-189952D01*
Y-186659D01*
X-377732Y-186482D01*
G02X-373550Y-186868I2088J-223D01*
G01X-373551Y-186877D01*
Y-189733D01*
X-373550Y-189743D01*
G02X-377732Y-190129I-2094J-162D01*
G37*
G36*
G01X-1247811D02*
X-1247830Y-189952D01*
Y-186659D01*
X-1247811Y-186482D01*
G02X-1243629Y-186868I2088J-223D01*
G01X-1243630Y-186877D01*
Y-189733D01*
X-1243629Y-189743D01*
G02X-1247811Y-190129I-2094J-162D01*
G37*
G36*
G01X-1450413Y-73798D02*
G02X-1451378Y-72526I-1587J-202D01*
G03X-1450687Y-72002I194J461D01*
G02X-1450693Y-71655I1587J202D01*
G03X-1451336Y-71131I-498J45D01*
G02X-1451114Y-68154I-464J1531D01*
G03X-1450400Y-67702I214J452D01*
G02X-1450399Y-67655I1600J2D01*
G03X-1451090Y-67179I-500J14D01*
G02X-1451090Y-64221I-610J1479D01*
G03X-1450400Y-63768I191J462D01*
G02X-1450366Y-63473I1600J-32D01*
G03X-1450731Y-63203I-245J51D01*
G02X-1450966Y-60292I-769J1403D01*
G03X-1450299Y-59840I167J471D01*
G02X-1449234Y-61408I1599J-60D01*
G03X-1449901Y-61860I-167J-471D01*
G02X-1449934Y-62127I-1599J61D01*
G03X-1449569Y-62397I245J-51D01*
G02X-1449410Y-65279I769J-1403D01*
G03X-1450100Y-65732I-191J-462D01*
G02X-1450101Y-65745I-1600J31D01*
G03X-1449410Y-66221I500J-14D01*
G02X-1449486Y-69146I610J-1479D01*
G03X-1450200Y-69598I-214J-452D01*
G02X-1450207Y-69745I-1600J-2D01*
G03X-1449564Y-70269I498J-45D01*
G02X-1449722Y-73274I464J-1531D01*
G03X-1450413Y-73798I-194J-461D01*
G37*
G36*
G01X-1450500Y-82159D02*
G02X-1451338Y-80793I-1599J-41D01*
G03X-1450600Y-80341I238J440D01*
G02X-1450592Y-80142I1599J41D01*
G03X-1451306Y-79642I-498J49D01*
G02X-1450408Y-78358I-694J1442D01*
G03X-1449694Y-78858I498J-49D01*
G02X-1449762Y-81707I694J-1442D01*
G03X-1450500Y-82159I-238J-440D01*
G37*
G36*
G01X-744813Y-104625D02*
G02X-746998I-1093J-2304D01*
G03Y-103721I-214J452D01*
G02X-744813I1093J2304D01*
G03Y-104625I214J-452D01*
G37*
G36*
G01X-1614892D02*
G02X-1617077I-1093J-2304D01*
G03Y-103721I-214J452D01*
G02X-1614892I1093J2304D01*
G03Y-104625I214J-452D01*
G37*
G36*
G01X-388872Y-125896D02*
G02X-390538Y-125817I-898J-1324D01*
G03X-390498Y-124964I-240J439D01*
G02X-388832Y-125043I898J1324D01*
G03X-388872Y-125896I240J-439D01*
G37*
G36*
G01X-744813Y-132184D02*
G02X-746998I-1093J-2304D01*
G03Y-131280I-214J452D01*
G02Y-126672I1093J2304D01*
G03Y-125769I-214J452D01*
G02Y-121160I1093J2304D01*
G03Y-120257I-214J452D01*
G02X-744813I1093J2304D01*
G03Y-121160I214J-452D01*
G02Y-125769I-1093J-2304D01*
G03Y-126672I214J-452D01*
G02Y-131280I-1093J-2304D01*
G03Y-132184I214J-452D01*
G37*
G36*
G01X-1614892D02*
G02X-1617077I-1093J-2304D01*
G03Y-131280I-214J452D01*
G02Y-126672I1093J2304D01*
G03Y-125769I-214J452D01*
G02Y-121160I1093J2304D01*
G03Y-120257I-214J452D01*
G02X-1614892I1093J2304D01*
G03Y-121160I214J-452D01*
G02Y-125769I-1093J-2304D01*
G03Y-126672I214J-452D01*
G02Y-131280I-1093J-2304D01*
G03Y-132184I214J-452D01*
G37*
G36*
G01X-294341Y-138090D02*
G02X-296526I-1093J-2304D01*
G03Y-137186I-214J452D01*
G02X-294341I1093J2304D01*
G03Y-138090I214J-452D01*
G37*
G36*
G01X-1164419D02*
G02X-1166604I-1093J-2304D01*
G03Y-137186I-214J452D01*
G02X-1164419I1093J2304D01*
G03Y-138090I214J-452D01*
G37*
G36*
G01X-317963Y-143208D02*
G02X-320148I-1093J-2304D01*
G03Y-142304I-214J452D01*
G02Y-137696I1093J2304D01*
G03Y-136792I-214J452D01*
G02X-317963I1093J2304D01*
G03Y-137696I214J-452D01*
G02Y-142304I-1093J-2304D01*
G03Y-143208I214J-452D01*
G37*
G36*
G01X-1188041D02*
G02X-1190226I-1093J-2304D01*
G03Y-142304I-214J452D01*
G02Y-137696I1093J2304D01*
G03Y-136792I-214J452D01*
G02X-1188041I1093J2304D01*
G03Y-137696I214J-452D01*
G02Y-142304I-1093J-2304D01*
G03Y-143208I214J-452D01*
G37*
G36*
G01X-436518Y-147362D02*
G02X-438410Y-144838I-5412J-2087D01*
G03X-437619Y-144333I303J397D01*
G02X-435811Y-146743I3564J789D01*
G03X-436518Y-147362I-240J-438D01*
G37*
G36*
G01X-1306597D02*
G02X-1308489Y-144838I-5412J-2087D01*
G03X-1307698Y-144333I303J397D01*
G02X-1305890Y-146743I3564J789D01*
G03X-1306597Y-147362I-240J-438D01*
G37*
G36*
G01X-294341Y-154625D02*
G02X-296526I-1093J-2304D01*
G03Y-153721I-214J452D01*
G02X-294341I1093J2304D01*
G03Y-154625I214J-452D01*
G37*
G36*
G01X-310089D02*
G02X-312274I-1093J-2304D01*
G03Y-153721I-214J452D01*
G02Y-149113I1093J2304D01*
G03Y-148210I-214J452D01*
G02Y-143601I1093J2304D01*
G03Y-142698I-214J452D01*
G02Y-138090I1093J2304D01*
G03Y-137186I-214J452D01*
G02X-310089I1093J2304D01*
G03Y-138090I214J-452D01*
G02Y-142698I-1093J-2304D01*
G03Y-143601I214J-452D01*
G02Y-148210I-1093J-2304D01*
G03Y-149113I214J-452D01*
G02Y-153721I-1093J-2304D01*
G03Y-154625I214J-452D01*
G37*
G36*
G01X-1164419D02*
G02X-1166604I-1093J-2304D01*
G03Y-153721I-214J452D01*
G02X-1164419I1093J2304D01*
G03Y-154625I214J-452D01*
G37*
G36*
G01X-1180167D02*
G02X-1182352I-1093J-2304D01*
G03Y-153721I-214J452D01*
G02Y-149113I1093J2304D01*
G03Y-148210I-214J452D01*
G02Y-143601I1093J2304D01*
G03Y-142698I-214J452D01*
G02Y-138090I1093J2304D01*
G03Y-137186I-214J452D01*
G02X-1180167I1093J2304D01*
G03Y-138090I214J-452D01*
G02Y-142698I-1093J-2304D01*
G03Y-143601I214J-452D01*
G02Y-148210I-1093J-2304D01*
G03Y-149113I214J-452D01*
G02Y-153721I-1093J-2304D01*
G03Y-154625I214J-452D01*
G37*
G36*
G01X-302215Y-159743D02*
G02X-304400I-1093J-2304D01*
G03Y-158840I-214J452D01*
G02Y-154231I1093J2304D01*
G03Y-153328I-214J452D01*
G02Y-148720I1093J2304D01*
G03Y-147816I-214J452D01*
G02Y-143208I1093J2304D01*
G03Y-142304I-214J452D01*
G02Y-137696I1093J2304D01*
G03Y-136792I-214J452D01*
G02X-302215I1093J2304D01*
G03Y-137696I214J-452D01*
G02Y-142304I-1093J-2304D01*
G03Y-143208I214J-452D01*
G02Y-147816I-1093J-2304D01*
G03Y-148720I214J-452D01*
G02Y-153328I-1093J-2304D01*
G03Y-154231I214J-452D01*
G02Y-158840I-1093J-2304D01*
G03Y-159743I214J-452D01*
G37*
G36*
G01X-317963D02*
G02X-320148I-1093J-2304D01*
G03Y-158840I-214J452D01*
G02X-317963I1093J2304D01*
G03Y-159743I214J-452D01*
G37*
G36*
G01X-1172293D02*
G02X-1174478I-1093J-2304D01*
G03Y-158840I-214J452D01*
G02Y-154231I1093J2304D01*
G03Y-153328I-214J452D01*
G02Y-148720I1093J2304D01*
G03Y-147816I-214J452D01*
G02Y-143208I1093J2304D01*
G03Y-142304I-214J452D01*
G02Y-137696I1093J2304D01*
G03Y-136792I-214J452D01*
G02X-1172293I1093J2304D01*
G03Y-137696I214J-452D01*
G02Y-142304I-1093J-2304D01*
G03Y-143208I214J-452D01*
G02Y-147816I-1093J-2304D01*
G03Y-148720I214J-452D01*
G02Y-153328I-1093J-2304D01*
G03Y-154231I214J-452D01*
G02Y-158840I-1093J-2304D01*
G03Y-159743I214J-452D01*
G37*
G36*
G01X-1188041D02*
G02X-1190226I-1093J-2304D01*
G03Y-158840I-214J452D01*
G02X-1188041I1093J2304D01*
G03Y-159743I214J-452D01*
G37*
G36*
G01X-127569Y-171160D02*
G02X-129754I-1093J-2304D01*
G03Y-170257I-214J452D01*
G02X-127569I1093J2304D01*
G03Y-171160I214J-452D01*
G37*
G36*
G01X-997648D02*
G02X-999833I-1093J-2304D01*
G03Y-170257I-214J452D01*
G02X-997648I1093J2304D01*
G03Y-171160I214J-452D01*
G37*
G36*
G01X-276690Y-178957D02*
G02Y-177443I-1410J757D01*
G03X-275810I440J237D01*
G02Y-178957I1410J-757D01*
G03X-276690I-440J-237D01*
G37*
G36*
G01X-119695Y-176279D02*
G02X-121880I-1093J-2304D01*
G03Y-175375I-214J452D01*
G02X-119695I1093J2304D01*
G03Y-176279I214J-452D01*
G37*
G36*
G01X-989774D02*
G02X-991959I-1093J-2304D01*
G03Y-175375I-214J452D01*
G02X-989774I1093J2304D01*
G03Y-176279I214J-452D01*
G37*
G36*
G01X-1248991Y-179958D02*
G02X-1250200Y-178368I-1600J38D01*
G03X-1249578Y-177895I122J485D01*
G02X-1246560Y-177192I1600J-38D01*
G03X-1245682Y-177208I443J231D01*
G02X-1242793Y-177438I1391J-791D01*
G03X-1242043Y-177676I468J175D01*
G02X-1239679Y-178350I901J-1322D01*
G03X-1238929Y-178553I457J203D01*
G02X-1239455Y-180498I937J-1297D01*
G03X-1240205Y-180295I-457J-203D01*
G02X-1242640Y-179559I-937J1297D01*
G03X-1243390Y-179321I-468J-175D01*
G02X-1245710Y-178739I-901J1322D01*
G03X-1246588Y-178724I-443J-231D01*
G02X-1248369Y-179485I-1391J791D01*
G03X-1248991Y-179958I-122J-485D01*
G37*
G36*
G01X-1277879Y-180184D02*
G02X-1279022Y-179032I-1550J-395D01*
G03X-1278410Y-178425I127J484D01*
G02X-1277267Y-179577I1550J395D01*
G03X-1277879Y-180184I-127J-484D01*
G37*
G36*
G01X-378147Y-180281D02*
G02X-379660Y-179506I-1375J-819D01*
G03X-379274Y-178752I-43J498D01*
G02X-376482Y-177192I1375J819D01*
G03X-375604Y-177208I443J231D01*
G02X-372714Y-177438I1391J-791D01*
G03X-371964Y-177676I468J175D01*
G02X-369600Y-178350I901J-1322D01*
G03X-368850Y-178553I457J203D01*
G02X-369376Y-180498I937J-1297D01*
G03X-370126Y-180295I-457J-203D01*
G02X-372562Y-179559I-937J1297D01*
G03X-373312Y-179321I-468J-175D01*
G02X-375631Y-178739I-901J1322D01*
G03X-376509Y-178724I-443J-231D01*
G02X-377761Y-179527I-1391J791D01*
G03X-378147Y-180281I43J-498D01*
G37*
G36*
G01X-404627Y-181766D02*
G02X-406453I-913J-1314D01*
G03Y-180944I-285J411D01*
G02X-404627I913J1314D01*
G03Y-181766I285J-411D01*
G37*
G54D40*
X-1639488Y-27500D03*
X-1644488D03*
X-1654488Y-27300D03*
X-1649488Y-27400D03*
X-1634488Y-27600D03*
X-1629488Y-27700D03*
X-1618400Y-71600D03*
X-1618300Y-63100D03*
X-1621600Y-61100D03*
Y-65100D03*
X-1618500Y-67200D03*
X-1621600Y-69400D03*
X-1615000Y-37500D03*
Y-27500D03*
Y-32500D03*
X-1610000Y-37500D03*
Y-32500D03*
Y-27500D03*
X-1600000Y-37500D03*
Y-27500D03*
Y-32500D03*
X-1605000Y-37500D03*
Y-32500D03*
Y-27500D03*
X-1595000Y-37500D03*
Y-32500D03*
Y-27500D03*
X-1580000Y-42500D03*
Y-47500D03*
X-1585000Y-42500D03*
Y-47500D03*
X-1590000D03*
Y-42500D03*
X-1580000Y-27500D03*
Y-32500D03*
Y-37500D03*
X-1585000Y-32500D03*
Y-27500D03*
Y-37500D03*
X-1590000D03*
Y-32500D03*
Y-27500D03*
X-1565000Y-42500D03*
Y-47500D03*
X-1575000Y-42500D03*
Y-47500D03*
X-1570000Y-42500D03*
Y-47500D03*
X-1565000Y-27500D03*
Y-32500D03*
Y-37500D03*
X-1575000Y-27500D03*
Y-32500D03*
Y-37500D03*
X-1570000Y-32500D03*
Y-27500D03*
Y-37500D03*
X-1555000Y-47500D03*
Y-42500D03*
X-1550000Y-47500D03*
Y-42500D03*
X-1560000D03*
Y-47500D03*
X-1545000D03*
Y-42500D03*
Y-37500D03*
Y-32500D03*
Y-27500D03*
X-1555000Y-37500D03*
Y-32500D03*
Y-27500D03*
X-1550000Y-37500D03*
Y-32500D03*
Y-27500D03*
X-1560000D03*
Y-32500D03*
Y-37500D03*
X-1530000Y-120300D03*
X-1535000Y-42500D03*
Y-47500D03*
X-1540000Y-42500D03*
Y-47500D03*
X-1535000Y-32500D03*
X-1540000Y-37500D03*
Y-32500D03*
X-1535000Y-37500D03*
X-1497000Y-81700D03*
X-1496693Y-76890D03*
Y-71890D03*
X-1486693D03*
X-1491693D03*
X-1476693D03*
X-1481693D03*
X-1471693D03*
X-1476693Y-76890D03*
X-1481693D03*
X-1471693D03*
X-1466693D03*
Y-81890D03*
Y-71890D03*
X-1461693D03*
Y-76890D03*
X-1450000Y-175000D03*
X-1437500Y-162500D03*
X-1450000Y-150000D03*
Y-125000D03*
X-1443500Y-94000D03*
X-1450000Y-100000D03*
X-1448900Y-76100D03*
X-1434892Y-40389D03*
Y-50389D03*
Y-45389D03*
Y-35389D03*
X-1425000Y-175000D03*
X-1424500Y-100000D03*
X-1425000Y-87500D03*
Y-62500D03*
X-1419892Y-50389D03*
Y-40389D03*
Y-45389D03*
X-1427392Y-50389D03*
Y-45389D03*
Y-40389D03*
X-1419892Y-35389D03*
X-1427392D03*
X-1432000Y-18000D03*
X-1412500Y-162500D03*
X-1412000Y-87000D03*
X-1412500Y-75000D03*
X-1404892Y-50389D03*
Y-45389D03*
Y-40389D03*
X-1412392Y-50389D03*
Y-45389D03*
Y-40389D03*
X-1404892Y-35389D03*
X-1412392D03*
X-1407000Y-18000D03*
X-1407500Y14500D03*
X-1400000Y-175000D03*
X-1387500Y-162500D03*
X-1400000Y-150000D03*
X-1387500Y-137500D03*
X-1400000Y-125000D03*
X-1387500Y-112500D03*
X-1400500Y-87000D03*
X-1391000Y-96500D03*
X-1387500Y-75000D03*
X-1400000Y-62500D03*
X-1389892Y-40389D03*
Y-45389D03*
Y-50389D03*
X-1397392Y-40389D03*
Y-45389D03*
Y-50389D03*
X-1389892Y-35389D03*
X-1397392D03*
X-1395000Y-8000D03*
X-1375000Y-62500D03*
X-1382392Y-40389D03*
Y-45389D03*
Y-50389D03*
Y-35389D03*
X-1382500Y-18000D03*
Y-500D03*
Y14500D03*
X-1362500Y-75000D03*
X-1370000Y-8000D03*
X-1357500Y-500D03*
X-1370000Y7000D03*
X-1357500Y14500D03*
X-1350000Y-62500D03*
X-1345000Y-8000D03*
Y7000D03*
X-1335400Y-75000D03*
Y-37600D03*
X-1332500Y-500D03*
Y14500D03*
X-1322228Y-88400D03*
X-1316728Y-89200D03*
X-1321000Y-94850D03*
X-1317700Y-72700D03*
X-1310559Y-74200D03*
X-1317700Y-60200D03*
X-1310559Y-68700D03*
Y-63200D03*
Y-57700D03*
Y-41200D03*
Y-52200D03*
X-1311200Y-30200D03*
X-1310559Y-35700D03*
X-1320000Y7000D03*
X-1318500Y-6000D03*
X-1306850Y-95000D03*
X-1300350Y-88500D03*
X-1293500Y-80000D03*
X-1302400Y-84100D03*
X-1297995Y-58405D03*
X-1298400Y-63200D03*
X-1298780Y-52200D03*
X-1298000Y-41200D03*
X-1298700Y-35700D03*
X-1295400Y-13400D03*
X-1307500Y14500D03*
X-1282500D03*
X-1248860Y-150200D03*
X-1246390Y-153490D03*
X-1249016Y-144800D03*
X-1250660Y-140480D03*
X-1257500Y-45000D03*
Y-20000D03*
Y14500D03*
X-1236310Y-140390D03*
X-1232500Y-20000D03*
Y14500D03*
X-1202580Y-176300D03*
X-1202100Y-103200D03*
X-1199500Y-3000D03*
X-1207500Y14500D03*
X-1191200Y-40500D03*
X-1191000Y-46500D03*
X-1191900Y-29500D03*
X-1190800Y-23450D03*
X-1191200Y-12128D03*
X-1192359Y-5800D03*
X-1191500Y0D03*
X-1176100Y-114800D03*
X-1170300Y-114600D03*
X-1172500Y-44000D03*
X-1173200Y-49700D03*
X-1178900Y-46700D03*
X-1172500Y-38500D03*
X-1178950Y-23250D03*
X-1171800Y-26950D03*
X-1178800Y-34800D03*
X-1177800Y-12100D03*
X-1171800Y-16250D03*
X-1178800Y-5800D03*
X-1172100Y-5400D03*
X-1182500Y14500D03*
X-1160000Y-115100D03*
X-1154200Y-103100D03*
X-1154400Y-107900D03*
X-1159700Y-43900D03*
X-1160150Y-26750D03*
X-1159800Y-33100D03*
X-1151500Y-15000D03*
X-1158700Y-16250D03*
X-1159700Y-5750D03*
X-1157500Y14500D03*
X-1137500Y-15000D03*
X-1124700Y-180000D03*
X-1134579Y-179850D03*
X-1125000Y-101700D03*
X-1121870Y-104330D03*
X-1126000Y-2500D03*
X-1132500Y14500D03*
X-1113328Y-182209D03*
X-1107828Y-182300D03*
X-1114979Y-170700D03*
X-1106979D03*
X-1114500Y-129000D03*
X-1110500D03*
X-1115490Y-104240D03*
X-1118701Y-101759D03*
X-1112402Y-101600D03*
X-1109300Y-104200D03*
X-1106102Y-102100D03*
X-1107700Y-73400D03*
Y-63100D03*
X-1107800Y-68200D03*
X-1111500Y-15000D03*
X-1107500Y14500D03*
X-1095600Y-179600D03*
X-1102953Y-104200D03*
X-1099400Y-90200D03*
X-1093400D03*
X-1100000Y-2500D03*
X-1084600Y-179850D03*
X-1073000Y-90300D03*
X-1082500Y14500D03*
X-1056900Y-56300D03*
X-1063600Y-56600D03*
X-1062000Y-29200D03*
X-1061900Y-5200D03*
X-1070000Y14500D03*
X-1045100Y-52900D03*
X-1044300Y-47661D03*
X-1051200Y-44100D03*
X-1054900Y-29800D03*
X-1045400Y-38000D03*
X-1051400Y-26000D03*
X-1047289Y-26300D03*
X-1041300Y-10100D03*
Y-16500D03*
X-1054600Y-5100D03*
X-1050811Y2600D03*
X-1047300Y-2700D03*
X-1045000Y14500D03*
X-1033843Y-128576D03*
X-1017670Y-123250D03*
X-1022140Y-122960D03*
X-1020000Y14500D03*
X-997500Y-7500D03*
X-995000Y14500D03*
X-970000Y-7500D03*
Y14500D03*
X-945000Y-7500D03*
Y14500D03*
X-922500Y-159500D03*
Y-132500D03*
Y-107500D03*
Y-82500D03*
Y-57500D03*
Y-7500D03*
X-922000Y14500D03*
X-910000Y-170000D03*
Y-95000D03*
Y-70000D03*
Y-45000D03*
Y-20000D03*
Y5000D03*
X-885000Y-170000D03*
X-897500Y-159500D03*
Y-132500D03*
Y-107500D03*
X-885000Y-95000D03*
X-897500Y-82500D03*
X-885000Y-70000D03*
X-897500Y-57500D03*
X-885000Y-45000D03*
Y-20000D03*
X-897500Y-7500D03*
X-885000Y5000D03*
X-897500Y14500D03*
X-872500Y-159500D03*
Y-132500D03*
Y-107500D03*
Y-82500D03*
Y-57500D03*
Y-7500D03*
Y14500D03*
X-860000Y-170000D03*
Y-95000D03*
Y-70000D03*
Y-45000D03*
Y-20000D03*
Y5000D03*
X-847500Y-159500D03*
Y-132500D03*
Y-107500D03*
Y-82500D03*
Y-57500D03*
Y-7500D03*
X-848000Y14500D03*
X-822500Y-159500D03*
Y-132500D03*
X-835000Y-120000D03*
X-822500Y-107500D03*
X-835000Y-95000D03*
X-822500Y-82500D03*
X-835000Y-70000D03*
X-822500Y-57500D03*
X-835000Y-45000D03*
X-822500Y-7500D03*
X-835000Y-20000D03*
X-822500Y14500D03*
X-810000Y-20000D03*
Y5000D03*
X-797500Y-7500D03*
Y14500D03*
X-785000Y-20000D03*
Y5000D03*
X-760000Y-145000D03*
X-772500Y-132500D03*
X-760000Y-120000D03*
X-772500Y-107500D03*
X-760000Y-95000D03*
X-772500Y-82500D03*
X-760000Y-70000D03*
X-772500Y-57500D03*
X-760000Y-45000D03*
Y-20000D03*
X-772500Y-7500D03*
X-760000Y5000D03*
X-772500Y14500D03*
X-747500Y-57500D03*
Y-7500D03*
Y14500D03*
X-735000Y-45000D03*
Y-20000D03*
Y5000D03*
X-722500Y-57500D03*
Y-7500D03*
Y14500D03*
X-710000Y-45000D03*
X-697500Y-7500D03*
X-710000Y-20000D03*
Y5000D03*
X-697500Y14500D03*
X-685000Y-45000D03*
Y-20000D03*
Y5000D03*
X-672500Y-7500D03*
Y14500D03*
X-649700Y-117200D03*
X-655500Y-25500D03*
X-642500D03*
Y-37500D03*
Y-12500D03*
X-645000Y14500D03*
X-626625Y-81614D03*
X-626614Y-76890D03*
Y-71890D03*
X-621614D03*
X-616614D03*
X-630000Y-37500D03*
X-616000Y-25500D03*
X-606614Y-71890D03*
X-611614D03*
X-601614D03*
X-606614Y-76890D03*
X-611614D03*
X-601614D03*
X-602500Y-25000D03*
Y0D03*
X-591200Y-179700D03*
X-591614Y-71890D03*
X-596614Y-76890D03*
Y-81890D03*
X-591614Y-76890D03*
X-596614Y-71890D03*
X-590000Y-37500D03*
Y-12500D03*
Y12500D03*
X-577500Y-165000D03*
Y-140000D03*
Y-115000D03*
Y-65000D03*
Y-25000D03*
Y0D03*
X-565000Y-177500D03*
Y-152500D03*
Y-37500D03*
Y-12500D03*
Y12500D03*
X-540000Y-177500D03*
X-552500Y-165000D03*
X-540000Y-152500D03*
X-552500Y-140000D03*
X-540000Y-127500D03*
Y-102500D03*
Y-77500D03*
X-552500Y-65000D03*
Y-25000D03*
X-540000Y-37500D03*
Y-12500D03*
X-552500Y0D03*
X-540000Y12500D03*
X-527500Y-165000D03*
Y-140000D03*
Y-115000D03*
Y-90000D03*
Y-65000D03*
Y-25000D03*
Y0D03*
X-515000Y-177500D03*
Y-152500D03*
Y-127500D03*
Y-102500D03*
Y-77500D03*
Y-37500D03*
Y-12500D03*
Y12500D03*
X-490000Y-102500D03*
X-502500Y-90000D03*
X-490000Y-77500D03*
X-502500Y-65000D03*
X-490000Y-37500D03*
X-502500Y-25000D03*
X-490000Y-12500D03*
X-502500Y0D03*
X-490000Y12500D03*
X-477500Y-25000D03*
Y0D03*
X-462000Y-73500D03*
X-465000Y-37500D03*
Y12500D03*
X-453628Y-88300D03*
X-448128Y-88800D03*
X-452700Y-69000D03*
X-449100Y-60841D03*
X-442800Y-46600D03*
X-449000Y6500D03*
X-448600Y-5900D03*
X-432118Y-87082D03*
X-436771Y-92400D03*
X-441959Y-74100D03*
X-429900Y-79600D03*
X-441959Y-68600D03*
X-429000Y-57600D03*
X-430700Y-63100D03*
X-441959D03*
Y-57600D03*
X-430180Y-52100D03*
X-429400Y-41100D03*
X-441959D03*
Y-52100D03*
X-430400Y-35600D03*
X-441959D03*
X-431000Y6500D03*
X-440000Y12500D03*
X-424500Y-26500D03*
X-424600Y-14400D03*
X-380421Y-147000D03*
X-375800Y-154000D03*
X-373620Y-124430D03*
X-374800Y-105700D03*
X-333450Y-174950D03*
X-321600Y-113500D03*
X-316500D03*
X-321700Y-42000D03*
X-321500Y-47500D03*
X-322400Y-31000D03*
X-321300Y-24950D03*
X-321800Y-7300D03*
X-321700Y-13628D03*
X-321859Y-1500D03*
X-312100Y-113500D03*
X-303200Y-43300D03*
Y-48800D03*
X-309400Y-47700D03*
X-302300Y-25950D03*
X-302900Y-37900D03*
X-309400Y-25100D03*
X-308500Y-36400D03*
X-308800Y-7400D03*
X-302500Y-15200D03*
X-307900Y-13628D03*
X-302300Y-4450D03*
X-286500Y-113700D03*
X-296400Y-113500D03*
X-290400Y-43200D03*
X-289500Y-32500D03*
X-290800Y-26000D03*
X-290700Y-9750D03*
X-290300Y-4400D03*
X-282300Y-113700D03*
X-254800Y-180000D03*
X-265200Y-179850D03*
X-254921Y-101700D03*
X-237750Y-182300D03*
X-243250Y-182209D03*
X-244900Y-170700D03*
X-244300Y-129300D03*
X-240300D03*
X-245411Y-104240D03*
X-248622Y-101759D03*
X-251792Y-104330D03*
X-242323Y-101600D03*
X-239222Y-104200D03*
X-225400Y-179800D03*
X-236900Y-170700D03*
X-236024Y-102100D03*
X-232874Y-104200D03*
X-214500Y-179800D03*
X-196900Y-176500D03*
X-201600Y-176600D03*
X-206100D03*
X-191000Y-56400D03*
X-190300Y-28900D03*
Y-4200D03*
X-185900Y-56200D03*
X-179800Y-43500D03*
X-182900Y-29800D03*
X-176350Y-27200D03*
X-179811Y-21300D03*
X-183200Y-4600D03*
X-179011Y4500D03*
X-175100Y-1800D03*
X-163764Y-128576D03*
X-173800Y-47300D03*
X-173200Y-52400D03*
X-170200Y-34470D03*
X-170500Y-10000D03*
X-170300Y-16500D03*
X-150900Y-121100D03*
X-152400Y-125050D03*
G54D41*
X-1615984Y-156535D03*
X-745906D03*
G54D42*
X-994488Y-93068D03*
Y-78108D03*
Y-63147D03*
Y-48187D03*
X-991535Y-98580D03*
Y-83620D03*
Y-68659D03*
Y-53698D03*
X-951181Y-93068D03*
X-948228Y-98580D03*
Y-83620D03*
X-951181Y-78108D03*
X-948228Y-68659D03*
X-951181Y-63147D03*
X-948228Y-53698D03*
X-951181Y-48187D03*
X-121457Y-98580D03*
X-124409Y-93068D03*
X-121457Y-83620D03*
X-124409Y-78108D03*
X-121457Y-68659D03*
X-124409Y-63147D03*
X-121457Y-53698D03*
X-124409Y-48187D03*
X-81102Y-93068D03*
Y-78108D03*
Y-63147D03*
Y-48187D03*
X-78150Y-98580D03*
Y-83620D03*
Y-68659D03*
Y-53698D03*
G54D38*
X-1649000Y-105752D03*
Y-113626D03*
X-793728Y-153976D03*
Y-146102D03*
G54D37*
X-1649000Y-121500D03*
X-1296260Y-175039D03*
X-1304134D03*
X-1296260Y-167165D03*
X-1304134D03*
X-1296260Y-159291D03*
X-1304134D03*
X-1296260Y-143543D03*
Y-135669D03*
X-1304134D03*
X-1296260Y-127795D03*
X-1304134D03*
X-793728Y-161850D03*
X-426181Y-175039D03*
X-434055D03*
X-426181Y-167165D03*
X-434055D03*
X-426181Y-159291D03*
X-434055D03*
X-426181Y-143543D03*
Y-135669D03*
X-434055D03*
X-426181Y-127795D03*
X-434055D03*
G54D33*
X-1488693Y-178940D03*
X-1476693Y-64840D03*
X-618614Y-178940D03*
X-606614Y-64840D03*
G54D39*
X-1649000Y-97878D03*
X-793728Y-138228D03*
G54D31*
X-341929Y-142362D03*
X-408071D03*
X-1212008D03*
X-1278150D03*
G54D44*
X-806854Y-83100D03*
X-785200D03*
G54D43*
X-806854Y-99635D03*
X-785200D03*
G54D36*
X-1094291Y-126220D03*
X-224213D03*
G54D35*
X-1132087D03*
X-262008D03*
G54D34*
X-1410000Y0D03*
X0Y-136453D03*
X0Y0D03*
G54D32*
X-486810Y-167165D03*
X-1051613D03*
Y-118937D03*
X-486810D03*
X-181534Y-167165D03*
Y-118937D03*
%LPD*%
G75*
G36*
G01X-903784Y-186850D02*
Y-184850D01*
X-869784D01*
Y-186850D01*
X-903784D01*
G37*
G54D10*
X-1645906Y-167953D03*
X-1522728Y-154950D03*
X-1047676Y-78740D03*
X-652638Y-154950D03*
X-177597Y-78740D03*
X6890Y-167953D03*
G54D11*
X-1656906D03*
X-1645906Y-178953D03*
X-1653906Y-175453D03*
X-1653406Y-159953D03*
X-1645906Y-156953D03*
X-1634906Y-167953D03*
X-1637906Y-175453D03*
X-1638406Y-159953D03*
X-1530728Y-162450D03*
X-1533728Y-154950D03*
X-1530228Y-146950D03*
X-1522728Y-165950D03*
X-1514728Y-162450D03*
X-1515228Y-146950D03*
X-1522728Y-143950D03*
X-1511728Y-154950D03*
X-1058676Y-78740D03*
X-1047676Y-89740D03*
X-1055676Y-86240D03*
X-1055176Y-70740D03*
X-1047676Y-67740D03*
X-1039676Y-86240D03*
X-1040176Y-70740D03*
X-1036676Y-78740D03*
X-663638Y-154950D03*
X-652638Y-165950D03*
X-660638Y-162450D03*
X-660138Y-146950D03*
X-652638Y-143950D03*
X-641638Y-154950D03*
X-644638Y-162450D03*
X-645138Y-146950D03*
X-177597Y-89740D03*
X-185597Y-86240D03*
X-188597Y-78740D03*
X-185097Y-70740D03*
X-177597Y-67740D03*
X-169597Y-86240D03*
X-170097Y-70740D03*
X-166597Y-78740D03*
X-4110Y-167953D03*
X6890Y-178953D03*
X-1110Y-175453D03*
X14390Y-159953D03*
X-610D03*
X6890Y-156953D03*
X17890Y-167953D03*
X14890Y-175453D03*
G54D20*
X-1025000Y-50942D03*
Y1459D03*
X-1015157Y-105312D03*
X-997441D03*
X-981693Y-50942D03*
Y1459D03*
X-971850Y-105312D03*
X-954134D03*
X-938386Y-50942D03*
Y1459D03*
X-145079Y-105312D03*
X-154921Y-50942D03*
Y1459D03*
X-127362Y-105312D03*
X-111614Y-50942D03*
Y1459D03*
X-101772Y-105312D03*
X-84055D03*
X-68307Y-50942D03*
Y1459D03*
G54D30*
G01X-1020800Y-457700D02*
G02X-1020300Y-458200I0J-500D01*
G01Y-458400D01*
G02X-1020900Y-459000I-600J0D01*
G01X-1021300D01*
G01X-1021800Y-460500D02*
Y-457700D01*
X-1020600D01*
G01X-1018340Y-459100D02*
G03I-2660J0D01*
G01X-1020700D02*
X-1020200Y-460500D01*
G54D21*
X-1015157Y-95824D03*
Y-80864D03*
Y-65903D03*
Y-50942D03*
X-1006299Y-95824D03*
X-997441D03*
X-1006299Y-80864D03*
X-997441D03*
X-1006299Y-65903D03*
X-997441D03*
X-1006299Y-50942D03*
X-997441D03*
X-971850Y-95824D03*
X-962992D03*
X-971850Y-80864D03*
X-962992D03*
X-971850Y-65903D03*
X-962992D03*
X-971850Y-50942D03*
X-962992D03*
X-954134Y-95824D03*
Y-80864D03*
Y-65903D03*
Y-50942D03*
X-145079Y-95824D03*
Y-80864D03*
Y-65903D03*
Y-50942D03*
X-136220Y-95824D03*
X-127362D03*
X-136220Y-80864D03*
X-127362D03*
X-136220Y-65903D03*
X-127362D03*
X-136220Y-50942D03*
X-127362D03*
X-101772Y-95824D03*
Y-80864D03*
Y-65903D03*
Y-50942D03*
X-92913Y-95824D03*
X-84055D03*
X-92913Y-80864D03*
X-84055D03*
X-92913Y-65903D03*
X-84055D03*
X-92913Y-50942D03*
X-84055D03*
G54D12*
X-1656000Y-135000D03*
X-1658500Y-31000D03*
X-1633000Y-135500D03*
X-1535063Y-22160D03*
X-1530063Y-12160D03*
Y-17160D03*
Y-22160D03*
X-1535063Y-12160D03*
Y-17160D03*
X-1524359Y-125359D03*
X-1515063Y-12160D03*
Y-17160D03*
Y-22160D03*
X-1525063Y-12160D03*
Y-17160D03*
X-1520063Y-12160D03*
Y-17160D03*
X-1525063Y-22160D03*
X-1520063D03*
X-1497043Y-169390D03*
X-1500063Y-12160D03*
Y-17160D03*
Y-22160D03*
X-1510063Y-12160D03*
Y-17160D03*
X-1505063Y-12160D03*
Y-17160D03*
X-1510063Y-22160D03*
X-1505063D03*
X-1497043Y-164390D03*
X-1486693Y-166890D03*
X-1497043Y-149390D03*
X-1486693Y-161890D03*
X-1491652Y-151849D03*
X-1491693Y-156890D03*
X-1497043Y-144390D03*
X-1491693Y-136890D03*
X-1486693Y-141890D03*
Y-146890D03*
X-1497043Y-124390D03*
Y-129390D03*
X-1486693Y-121890D03*
Y-126890D03*
X-1491693Y-131890D03*
X-1497043Y-109390D03*
Y-104390D03*
X-1486693Y-101890D03*
Y-106890D03*
X-1491693Y-111890D03*
Y-116890D03*
X-1497043Y-89390D03*
X-1486693Y-86890D03*
X-1491693Y-91890D03*
Y-96890D03*
X-1486693Y-76890D03*
X-1491693D03*
X-1486693Y-81890D03*
X-1485063Y-12160D03*
Y-17160D03*
Y-22160D03*
X-1495063Y-12160D03*
Y-17160D03*
X-1490063Y-12160D03*
Y-17160D03*
X-1495063Y-22160D03*
X-1490063D03*
X-1466693Y-166890D03*
X-1476693D03*
Y-161890D03*
X-1481693Y-156890D03*
Y-151890D03*
X-1471693D03*
Y-156890D03*
X-1466693Y-161890D03*
X-1481693Y-136890D03*
X-1471693D03*
X-1466693Y-141890D03*
X-1476693D03*
X-1466693Y-146890D03*
X-1476693D03*
X-1481693Y-131890D03*
X-1466693Y-121890D03*
X-1476693D03*
X-1466693Y-126890D03*
X-1476693D03*
X-1471693Y-131890D03*
X-1481693Y-111890D03*
Y-116890D03*
X-1466693Y-101890D03*
X-1476693D03*
X-1466693Y-106890D03*
X-1476693D03*
X-1471693Y-111890D03*
Y-116890D03*
X-1481693Y-91890D03*
Y-96890D03*
X-1466693Y-86890D03*
X-1476693D03*
X-1471693Y-91890D03*
Y-96890D03*
X-1476693Y-81890D03*
X-1475063Y-22160D03*
X-1470063Y-12160D03*
Y-17160D03*
Y-22160D03*
X-1480063Y-12160D03*
Y-17160D03*
X-1475063Y-12160D03*
Y-17160D03*
X-1480063Y-22160D03*
X-1461693Y-151890D03*
Y-156890D03*
Y-136890D03*
Y-131890D03*
X-1450000Y-112500D03*
X-1461693Y-111890D03*
Y-116890D03*
Y-91890D03*
Y-96890D03*
X-1465063Y-12160D03*
Y-17160D03*
Y-22160D03*
X-1437500Y-175000D03*
X-1450000Y-162500D03*
Y-137500D03*
X-1437500Y-100000D03*
X-1436500Y-87500D03*
X-1450000D03*
X-1435000Y1000D03*
X-1425000Y-162500D03*
X-1430500Y-93500D03*
X-1430000Y-75400D03*
X-1421250Y-81250D03*
X-1431500Y-81000D03*
X-1419500Y-18000D03*
X-1420000Y14500D03*
X-1412500Y-175000D03*
X-1406250Y-106250D03*
X-1412000Y-100500D03*
X-1418500Y-93500D03*
X-1406250Y-82500D03*
X-1412500Y-62500D03*
X-1387500Y-175000D03*
Y-150000D03*
X-1400000Y-162500D03*
X-1387300Y-133200D03*
X-1387500Y-125000D03*
X-1400100Y-131550D03*
X-1395000Y-106250D03*
X-1400000Y-112500D03*
X-1400500Y-96500D03*
X-1393750Y-82500D03*
X-1400000Y-75000D03*
X-1387500Y-62500D03*
X-1394500Y-18000D03*
X-1395000Y-500D03*
X-1395518Y14053D03*
X-1371250Y-112500D03*
X-1380000Y-106250D03*
X-1381250Y-82500D03*
X-1375000Y-75000D03*
X-1373800Y-52900D03*
X-1382500Y-8000D03*
Y7000D03*
X-1363750Y-106250D03*
X-1356250Y-82500D03*
X-1368750D03*
X-1362500Y-62500D03*
X-1356700Y-25600D03*
X-1357500Y-8000D03*
X-1370000Y-500D03*
X-1357500Y7000D03*
X-1370000Y14500D03*
X-1350600Y-75000D03*
X-1343200Y-82700D03*
X-1345000Y-500D03*
Y14500D03*
X-1330400Y-74900D03*
X-1324840Y-82120D03*
X-1337500Y-62500D03*
X-1324500Y-26959D03*
X-1332500Y-27500D03*
Y7000D03*
X-1313040Y-80810D03*
X-1310600Y-46690D03*
X-1320000Y-500D03*
Y14500D03*
X-1298800Y-30200D03*
X-1307500Y7000D03*
X-1295000Y14500D03*
X-1271813Y-181337D03*
X-1264267Y-181074D03*
X-1271813Y-185937D03*
X-1264013D03*
X-1263189Y-177998D03*
X-1272638D03*
X-1274213Y-157350D03*
X-1264764D03*
X-1265588Y-154080D03*
X-1273388D03*
Y-149480D03*
X-1265588D03*
X-1263925Y-146735D03*
X-1264060Y-141950D03*
X-1270000Y14500D03*
X-1248010Y-184405D03*
Y-192205D03*
X-1253740Y-177998D03*
X-1255315Y-157350D03*
X-1256125Y-146735D03*
Y-142135D03*
X-1257500Y-57500D03*
X-1230040Y-183080D03*
Y-187680D03*
X-1237840Y-183080D03*
Y-187680D03*
X-1243410Y-184405D03*
Y-192205D03*
X-1234843Y-177998D03*
X-1236418Y-157350D03*
X-1235593Y-136650D03*
Y-132050D03*
X-1245000Y-70000D03*
X-1232500Y-57500D03*
Y-45000D03*
X-1245000D03*
Y-20000D03*
Y14500D03*
X-1215945Y-177998D03*
X-1225394D03*
X-1217520Y-157350D03*
X-1226969D03*
X-1218290Y-152200D03*
X-1226090D03*
X-1218290Y-147600D03*
X-1226090D03*
X-1227793Y-136650D03*
Y-132050D03*
X-1220000Y14500D03*
X-1211720Y-169660D03*
Y-165060D03*
X-1203920D03*
Y-169660D03*
X-1199500Y5400D03*
X-1191500Y-34000D03*
X-1191000Y-18250D03*
X-1195000Y14500D03*
X-1179000Y-40500D03*
X-1172000Y-10750D03*
X-1171500Y-21750D03*
X-1170000Y14500D03*
X-1160000Y-38500D03*
X-1137500Y-2500D03*
X-1145000Y14500D03*
X-1124878Y-175150D03*
X-1124900Y-170650D03*
X-1125750Y-152883D03*
Y-157483D03*
X-1126575Y-147990D03*
Y-136730D03*
X-1124800Y-129000D03*
X-1120400D03*
X-1128810Y-104171D03*
X-1126000Y-15000D03*
X-1120000Y14500D03*
X-1117950Y-157483D03*
Y-152883D03*
X-1117126Y-136730D03*
X-1107677Y-148090D03*
Y-136730D03*
X-1117126Y-148090D03*
X-1111003Y-123960D03*
X-1106403D03*
Y-116160D03*
X-1111003D03*
X-1111500Y-2500D03*
X-1096278Y-170650D03*
X-1096200Y-175150D03*
X-1098228Y-148090D03*
Y-136730D03*
X-1099010Y-104183D03*
X-1100000Y-15000D03*
X-1095000Y14500D03*
X-1032500D03*
X-1015729Y-100550D03*
X-1012638Y-85886D03*
X-1015179Y-74100D03*
X-1012638Y-70873D03*
Y-56060D03*
X-1012860Y-41250D03*
X-1012500Y-7500D03*
X-1003380Y-86986D03*
X-1008429Y-91400D03*
X-999960Y-90706D03*
X-996670Y-75460D03*
X-1008719Y-75998D03*
X-999860Y-75848D03*
Y-60885D03*
X-1003780Y-56060D03*
X-994280Y-40890D03*
X-1007500Y14500D03*
X-983000Y-7500D03*
X-982500Y14500D03*
X-969331Y-100849D03*
Y-85886D03*
X-965512Y-90706D03*
X-971779Y-73800D03*
X-965412Y-75848D03*
Y-45922D03*
X-956653Y-90706D03*
X-960273Y-101049D03*
X-953250Y-75340D03*
X-956553Y-75848D03*
X-957779Y-57700D03*
X-956553Y-60885D03*
Y-45922D03*
X-957500Y-7500D03*
Y14500D03*
X-932500Y-7500D03*
Y14500D03*
X-922500Y-170000D03*
Y-120000D03*
Y-95000D03*
Y-70000D03*
Y-45000D03*
Y-20000D03*
Y5000D03*
X-910000Y-159500D03*
Y-132500D03*
Y-107500D03*
Y-82500D03*
Y-57500D03*
Y-7500D03*
X-909500Y14500D03*
X-897500Y-170000D03*
X-885000Y-159500D03*
Y-132500D03*
Y-107500D03*
X-897500Y-95000D03*
X-885000Y-82500D03*
X-897500Y-70000D03*
X-885000Y-57500D03*
X-897500Y-45000D03*
X-885000Y-7500D03*
X-897500Y-20000D03*
Y5000D03*
X-885000Y14500D03*
X-872500Y-170000D03*
Y-95000D03*
Y-70000D03*
Y-45000D03*
Y-20000D03*
Y5000D03*
X-860000Y-159500D03*
Y-132500D03*
Y-107500D03*
Y-82500D03*
Y-57500D03*
Y-7500D03*
Y14500D03*
X-847500Y-170000D03*
Y-95000D03*
Y-70000D03*
Y-45000D03*
Y-20000D03*
Y5000D03*
X-822500Y-170000D03*
X-835000Y-159500D03*
X-822500Y-145000D03*
X-835000Y-132500D03*
X-822500Y-120000D03*
X-835000Y-107500D03*
X-822500Y-95000D03*
X-835000Y-82500D03*
X-822500Y-70000D03*
X-835000Y-57500D03*
X-822500Y-45000D03*
Y-20000D03*
Y5000D03*
X-835500Y14500D03*
X-810000Y-170000D03*
Y-157500D03*
Y-145000D03*
Y-132500D03*
Y-120000D03*
Y-70000D03*
Y-57500D03*
Y-45000D03*
Y-7500D03*
Y14500D03*
X-797500Y-120000D03*
Y-70000D03*
Y-57500D03*
Y-45000D03*
Y-20000D03*
Y5000D03*
X-785500Y-120000D03*
X-785000Y-70000D03*
Y-57500D03*
Y-45000D03*
Y-7500D03*
Y14500D03*
X-772500Y-170000D03*
Y-145000D03*
X-760000Y-132500D03*
X-772500Y-120000D03*
X-760000Y-107500D03*
X-772500Y-95000D03*
X-760000Y-82500D03*
X-772500Y-70000D03*
X-760000Y-57500D03*
X-772500Y-45000D03*
X-760000Y-7500D03*
X-772500Y-20000D03*
Y5000D03*
X-760000Y14500D03*
X-747500Y-45000D03*
Y-20000D03*
Y5000D03*
X-735000Y-57500D03*
Y-7500D03*
Y14500D03*
X-722500Y-45000D03*
Y-20000D03*
Y5000D03*
X-697500Y-45000D03*
Y-20000D03*
X-710000Y-7500D03*
X-697500Y5000D03*
X-710000Y14500D03*
X-685000Y-7500D03*
Y14500D03*
X-672500Y-45000D03*
Y-20000D03*
Y5000D03*
X-655500Y-37500D03*
Y-12500D03*
Y-500D03*
X-660000Y14500D03*
X-643700Y-125400D03*
X-632500Y14500D03*
X-626964Y-169390D03*
Y-164390D03*
X-616614Y-166890D03*
X-621614Y-156890D03*
X-621573Y-151849D03*
X-616614Y-161890D03*
X-627200Y-151300D03*
X-621614Y-136890D03*
X-616614Y-146890D03*
Y-141890D03*
X-626900Y-141300D03*
X-621614Y-131890D03*
X-616614Y-126890D03*
Y-121890D03*
X-621614D03*
X-628700Y-130100D03*
X-621614Y-116890D03*
Y-111890D03*
X-626964Y-104390D03*
Y-109390D03*
X-616614Y-106890D03*
Y-101890D03*
X-621614Y-96890D03*
Y-91890D03*
X-626964Y-89390D03*
X-616614Y-86890D03*
Y-76890D03*
X-621614D03*
X-616614Y-81890D03*
X-616000Y-37500D03*
X-630000Y-25500D03*
Y-12500D03*
X-616000D03*
Y14500D03*
X-606614Y-166890D03*
X-601614Y-156890D03*
Y-151890D03*
X-611614D03*
Y-156890D03*
X-606614Y-161890D03*
Y-146890D03*
Y-141890D03*
X-601614Y-136890D03*
X-611614D03*
X-601614Y-131890D03*
X-606614Y-126890D03*
Y-121890D03*
X-611614Y-131890D03*
X-601614Y-116890D03*
Y-111890D03*
X-606614Y-106890D03*
Y-101890D03*
X-611614Y-116890D03*
Y-111890D03*
X-601614Y-96890D03*
Y-91890D03*
X-606614Y-86890D03*
X-611614Y-96890D03*
Y-91890D03*
X-606614Y-81890D03*
X-602500Y-37500D03*
Y-12500D03*
Y12500D03*
X-596614Y-166890D03*
X-591614Y-156890D03*
Y-151890D03*
X-596614Y-161890D03*
X-591614Y-136890D03*
X-596614Y-146890D03*
Y-141890D03*
X-591614Y-131890D03*
X-596614Y-126890D03*
Y-121890D03*
X-591614Y-116890D03*
Y-111890D03*
X-596614Y-106890D03*
Y-101890D03*
X-591614Y-96890D03*
Y-91890D03*
X-596614Y-86890D03*
X-590000Y-25000D03*
Y0D03*
X-577500Y-177500D03*
Y-152500D03*
Y-127500D03*
Y-37500D03*
Y-12500D03*
Y12500D03*
X-565000Y-165000D03*
Y-140000D03*
Y-65000D03*
Y-25000D03*
Y0D03*
X-540000Y-165000D03*
X-552500Y-177500D03*
Y-152500D03*
X-540000Y-140000D03*
Y-115000D03*
Y-90000D03*
Y-65000D03*
Y-25000D03*
X-552500Y-37500D03*
Y-12500D03*
X-540000Y0D03*
X-552500Y12500D03*
X-527500Y-177500D03*
Y-152500D03*
Y-127500D03*
Y-102500D03*
Y-77500D03*
Y-37500D03*
Y-12500D03*
Y12500D03*
X-515000Y-165000D03*
Y-140000D03*
Y-115000D03*
Y-90000D03*
Y-65000D03*
Y-25000D03*
Y0D03*
X-502500Y-102500D03*
X-490000Y-90000D03*
X-502500Y-77500D03*
Y-37500D03*
Y-12500D03*
X-490000Y0D03*
X-502500Y12500D03*
X-486421Y-26159D03*
X-477500Y-37500D03*
Y12500D03*
X-465000Y-25000D03*
X-461441Y6559D03*
X-456240Y-82020D03*
X-444440Y-80710D03*
X-454421Y-26959D03*
X-443941Y6559D03*
X-452500Y12500D03*
X-442000Y-29480D03*
X-427500Y12500D03*
X-413500D03*
X-401735Y-181337D03*
Y-185937D03*
X-402559Y-177998D03*
X-403309Y-149480D03*
Y-154080D03*
X-395509Y-149480D03*
Y-154080D03*
X-404134Y-157350D03*
X-402500Y12500D03*
X-394188Y-181074D03*
X-393935Y-185937D03*
X-383661Y-177998D03*
X-393110D03*
X-385237Y-157350D03*
X-394685D03*
X-393847Y-146735D03*
X-393981Y-141950D03*
X-386047Y-142135D03*
Y-146735D03*
X-386500Y-56500D03*
Y-44000D03*
Y-31500D03*
Y-19000D03*
Y-5500D03*
X-390000Y12500D03*
X-367761Y-183080D03*
Y-187680D03*
X-377931Y-184405D03*
Y-192205D03*
X-373331D03*
Y-184405D03*
X-364764Y-177998D03*
X-366339Y-157350D03*
X-365514Y-136650D03*
Y-132050D03*
X-374000Y-56500D03*
Y-44000D03*
Y-31500D03*
Y-19000D03*
X-365000Y12500D03*
X-377500D03*
X-359961Y-183080D03*
Y-187680D03*
X-355315Y-177998D03*
X-347441Y-157350D03*
X-356011Y-152200D03*
X-348211D03*
X-356890Y-157350D03*
X-357714Y-136650D03*
X-356011Y-147600D03*
X-348211D03*
X-357714Y-132050D03*
X-360500Y-87100D03*
X-353700Y-87600D03*
X-361500Y-56500D03*
X-348000Y-57000D03*
X-361500Y-44000D03*
X-348000D03*
Y-31500D03*
X-361500D03*
Y-19000D03*
X-348000D03*
X-352500Y12500D03*
X-341641Y-169660D03*
Y-165060D03*
X-333841D03*
Y-169660D03*
X-345866Y-177998D03*
X-347850Y-87050D03*
X-342400Y-87500D03*
X-336000Y-53000D03*
Y-28000D03*
Y-15500D03*
X-340000Y12500D03*
X-323500Y-65500D03*
X-327500Y12500D03*
X-315000D03*
X-302500D03*
X-285000Y-107400D03*
Y-103100D03*
X-290000Y12500D03*
X-277500D03*
X-254800Y-170650D03*
X-254800Y-175150D03*
X-255672Y-157483D03*
Y-152883D03*
X-256496Y-147990D03*
Y-136730D03*
X-254721Y-129000D03*
X-258732Y-104171D03*
X-255500Y-25500D03*
X-268000Y-13000D03*
X-255500D03*
Y-500D03*
X-268000D03*
X-265000Y12500D03*
X-247872Y-152883D03*
Y-157483D03*
X-247047Y-148090D03*
Y-136730D03*
X-240924Y-123960D03*
X-250321Y-129000D03*
X-240924Y-116160D03*
X-243000Y-40500D03*
Y-25500D03*
Y-13000D03*
Y-500D03*
X-240000Y12500D03*
X-252500D03*
X-226200Y-170650D03*
X-226121Y-175150D03*
X-237598Y-136730D03*
X-228150D03*
Y-148090D03*
X-237598D03*
X-236324Y-123960D03*
Y-116160D03*
X-228932Y-104183D03*
X-230000Y-13500D03*
X-230500Y-500D03*
X-227500Y12500D03*
X-215000D03*
X-202500D03*
X-177500D03*
X-190390Y12740D03*
X-165000Y12500D03*
X-145650Y-100550D03*
X-145100Y-74100D03*
X-152500Y12500D03*
X-138440Y-91390D03*
X-133301Y-86986D03*
X-142559Y-85886D03*
X-129882Y-90706D03*
X-129782Y-75998D03*
X-138640D03*
X-142559Y-70873D03*
X-133701Y-56060D03*
X-129782Y-60885D03*
X-142559Y-56060D03*
X-142130Y-41290D03*
X-139000Y-8500D03*
Y-21000D03*
X-140000Y12500D03*
X-127500D03*
X-126600Y-75410D03*
X-124590Y-41500D03*
X-114000Y-33500D03*
X-126500Y-21000D03*
X-114000Y-8500D03*
Y-21000D03*
X-126500Y-8500D03*
X-115000Y12500D03*
X-99252Y-100849D03*
Y-85886D03*
X-101700Y-73800D03*
X-101500Y-33500D03*
Y-21000D03*
Y-8500D03*
X-102500Y12500D03*
X-95433Y-90706D03*
X-86575D03*
X-90194Y-101049D03*
X-83310Y-75360D03*
X-95333Y-75848D03*
X-86475D03*
Y-60885D03*
X-87700Y-57700D03*
X-95333Y-45922D03*
X-86475D03*
X-89000Y-8500D03*
Y-21000D03*
X-90000Y12500D03*
X-74921Y-171500D03*
X-71500Y-158500D03*
Y-146000D03*
Y-133500D03*
X-71700Y-121000D03*
X-70500Y-108600D03*
X-76500Y-33500D03*
Y-21000D03*
Y-8500D03*
X-77500Y12500D03*
X-65000D03*
X-59500Y-173500D03*
Y-161000D03*
Y-136000D03*
Y-148500D03*
Y-123500D03*
Y-108500D03*
Y-96000D03*
Y-83500D03*
Y-71000D03*
Y-58500D03*
Y-46000D03*
Y-33500D03*
Y-8500D03*
Y-21000D03*
X-54500Y1500D03*
X-52500Y12500D03*
X-42500Y-173500D03*
X-43000Y-158500D03*
Y-146000D03*
X-47000Y-71000D03*
X-34500Y-83500D03*
Y-71000D03*
X-47000Y-83500D03*
X-34500Y-58500D03*
X-47000D03*
Y-46000D03*
X-34500D03*
Y-33500D03*
X-47000D03*
Y-21000D03*
X-34500Y-8500D03*
X-47000D03*
X-34500Y-21000D03*
X-42000Y1500D03*
X-40000Y12500D03*
X-18000Y-173500D03*
Y-158500D03*
X-30500D03*
Y-146000D03*
X-18000D03*
X-21150Y-83600D03*
X-22000Y-71000D03*
Y-58500D03*
Y-46000D03*
Y-33500D03*
Y-21000D03*
Y-8500D03*
X-27500Y12500D03*
X-9500Y-120000D03*
Y-108500D03*
Y-96000D03*
X-9350Y-83500D03*
X-9500Y-71000D03*
Y-58500D03*
Y-46000D03*
Y-33500D03*
Y-8500D03*
Y-21000D03*
X-17000Y1500D03*
X-2500Y12500D03*
X-15000D03*
X3000Y-120000D03*
Y-108500D03*
Y-96000D03*
Y-83500D03*
Y-71000D03*
Y-58500D03*
Y-46000D03*
Y-33500D03*
Y-21000D03*
Y-8500D03*
G54D22*
G01X-1184000Y-502500D02*
Y-512500D01*
G01X-1186683Y-502500D02*
X-1181317D01*
G01X-1176833Y-512500D02*
Y-502500D01*
X-1173917D01*
X-1172983Y-503000D01*
X-1172400Y-503667D01*
X-1172167Y-505000D01*
X-1172400Y-506333D01*
X-1173100Y-507167D01*
X-1173917Y-507667D01*
X-1176833D01*
G01X-1173917D02*
X-1172167Y-512500D01*
G01X-1167917D02*
X-1165000Y-502500D01*
X-1162083Y-512500D01*
G01X-1163133Y-509000D02*
X-1166867D01*
G01X-1155500Y-512500D02*
Y-508000D01*
X-1157833Y-502500D01*
G01X-1153167D02*
X-1155500Y-508000D01*
G01X-1135567Y-507167D02*
X-1135100Y-506667D01*
X-1134750Y-505834D01*
X-1134517Y-504667D01*
X-1134750Y-503667D01*
X-1135217Y-503000D01*
X-1136033Y-502500D01*
X-1139183D01*
Y-512500D01*
X-1135333D01*
X-1134517Y-511833D01*
X-1134050Y-510833D01*
X-1133817Y-509667D01*
X-1134050Y-508500D01*
X-1134750Y-507500D01*
X-1135567Y-507167D01*
X-1139183D01*
G01X-1129917Y-512500D02*
X-1127000Y-502500D01*
X-1124083Y-512500D01*
G01X-1125133Y-509000D02*
X-1128867D01*
G01X-1114933Y-503333D02*
X-1115633Y-502833D01*
X-1116450Y-502500D01*
X-1117383D01*
X-1118433Y-503000D01*
X-1119250Y-503833D01*
X-1119833Y-504833D01*
X-1120300Y-506500D01*
X-1120417Y-508000D01*
X-1120183Y-509500D01*
X-1119833Y-510500D01*
X-1119133Y-511500D01*
X-1118317Y-512167D01*
X-1117500Y-512500D01*
X-1116683D01*
X-1115867Y-512167D01*
X-1115167Y-511667D01*
X-1114583Y-511000D01*
G01X-1110567Y-512500D02*
Y-502500D01*
G01X-1106133D02*
X-1110567Y-508667D01*
G01X-1105433Y-512500D02*
X-1108583Y-505834D01*
G01X-1100833Y-512500D02*
Y-502500D01*
X-1098033D01*
X-1097100Y-503000D01*
X-1096400Y-504167D01*
X-1096167Y-505500D01*
X-1096400Y-506833D01*
X-1096983Y-507833D01*
X-1098033Y-508334D01*
X-1100833D01*
G01X-1091333Y-502500D02*
Y-512500D01*
X-1086667D01*
G01X-1082417D02*
X-1079500Y-502500D01*
X-1076583Y-512500D01*
G01X-1077633Y-509000D02*
X-1081367D01*
G01X-1072683Y-512500D02*
Y-502500D01*
X-1067317Y-512500D01*
Y-502500D01*
G01X-1058167Y-512500D02*
X-1062833D01*
Y-502500D01*
X-1058167D01*
G01X-1060033Y-507333D02*
X-1062833D01*
G01X-1043717Y-512500D02*
Y-502500D01*
X-1039283D01*
G01X-1040917Y-507333D02*
X-1043717D01*
G01X-1034917Y-512500D02*
X-1032000Y-502500D01*
X-1029083Y-512500D01*
G01X-1030133Y-509000D02*
X-1033867D01*
G01X-1021567Y-507167D02*
X-1021100Y-506667D01*
X-1020750Y-505834D01*
X-1020517Y-504667D01*
X-1020750Y-503667D01*
X-1021217Y-503000D01*
X-1022033Y-502500D01*
X-1025183D01*
Y-512500D01*
X-1021333D01*
X-1020517Y-511833D01*
X-1020050Y-510833D01*
X-1019817Y-509667D01*
X-1020050Y-508500D01*
X-1020750Y-507500D01*
X-1021567Y-507167D01*
X-1025183D01*
G01X-1002567D02*
X-1002100Y-506667D01*
X-1001750Y-505834D01*
X-1001517Y-504667D01*
X-1001750Y-503667D01*
X-1002217Y-503000D01*
X-1003033Y-502500D01*
X-1006183D01*
Y-512500D01*
X-1002333D01*
X-1001517Y-511833D01*
X-1001050Y-510833D01*
X-1000817Y-509667D01*
X-1001050Y-508500D01*
X-1001750Y-507500D01*
X-1002567Y-507167D01*
X-1006183D01*
G01X-985083Y-515833D02*
X-986250Y-514167D01*
X-986833Y-512500D01*
Y-505834D01*
X-986250Y-504167D01*
X-985083Y-502500D01*
G01X-975000Y-512500D02*
X-975933Y-512333D01*
X-976750Y-511667D01*
X-977450Y-510667D01*
X-977917Y-509500D01*
X-978150Y-508167D01*
Y-506833D01*
X-977917Y-505500D01*
X-977450Y-504333D01*
X-976750Y-503333D01*
X-975933Y-502667D01*
X-975000Y-502500D01*
X-974067Y-502667D01*
X-973250Y-503333D01*
X-972550Y-504333D01*
X-972083Y-505500D01*
X-971850Y-506833D01*
Y-508167D01*
X-972083Y-509500D01*
X-972550Y-510667D01*
X-973250Y-511667D01*
X-974067Y-512333D01*
X-975000Y-512500D01*
G01X-967950Y-511167D02*
X-967017Y-512000D01*
X-965967Y-512500D01*
X-965033D01*
X-964100Y-512000D01*
X-963400Y-511167D01*
X-963050Y-510000D01*
X-963283Y-508834D01*
X-963867Y-507833D01*
X-964917Y-507167D01*
X-966317Y-506833D01*
X-967133Y-506167D01*
X-967483Y-505000D01*
X-967250Y-503833D01*
X-966667Y-503000D01*
X-965850Y-502500D01*
X-965033D01*
X-964217Y-502833D01*
X-963517Y-503667D01*
G01X-958333Y-512500D02*
Y-502500D01*
X-955533D01*
X-954600Y-503000D01*
X-953900Y-504167D01*
X-953667Y-505500D01*
X-953900Y-506833D01*
X-954483Y-507833D01*
X-955533Y-508334D01*
X-958333D01*
G01X-945917Y-515833D02*
X-944750Y-514167D01*
X-944167Y-512500D01*
Y-505834D01*
X-944750Y-504167D01*
X-945917Y-502500D01*
G01X-902000Y-470000D02*
Y-460000D01*
X-903400Y-462000D01*
G01Y-470000D02*
X-900600D01*
G01X-892500Y-470333D02*
X-892733Y-470167D01*
Y-469833D01*
X-892500Y-469667D01*
X-892267Y-469833D01*
Y-470167D01*
X-892500Y-470333D01*
G01Y-465834D02*
X-892733Y-465667D01*
Y-465333D01*
X-892500Y-465167D01*
X-892267Y-465333D01*
Y-465667D01*
X-892500Y-465834D01*
G01X-883000Y-470000D02*
Y-460000D01*
X-884400Y-462000D01*
G01Y-470000D02*
X-881600D01*
G01X-785060Y-472187D02*
X-784127Y-473020D01*
X-783077Y-473520D01*
X-782143D01*
X-781210Y-473020D01*
X-780510Y-472187D01*
X-780160Y-471020D01*
X-780393Y-469854D01*
X-780977Y-468853D01*
X-782027Y-468187D01*
X-783427Y-467853D01*
X-784243Y-467187D01*
X-784593Y-466020D01*
X-784360Y-464853D01*
X-783777Y-464020D01*
X-782960Y-463520D01*
X-782143D01*
X-781327Y-463853D01*
X-780627Y-464687D01*
G01X-775560Y-473520D02*
Y-463520D01*
G01X-770660D02*
Y-473520D01*
G01Y-468520D02*
X-775560D01*
G01X-766527Y-473520D02*
X-763610Y-463520D01*
X-760693Y-473520D01*
G01X-761743Y-470020D02*
X-765477D01*
G01X-757610Y-463520D02*
X-755977Y-473520D01*
X-754110Y-463520D01*
X-752243Y-473520D01*
X-750610Y-463520D01*
G01X-668067Y-470500D02*
X-667367Y-471667D01*
X-666433Y-472333D01*
X-665383Y-472500D01*
X-664450Y-472333D01*
X-663517Y-471500D01*
X-662933Y-470500D01*
X-662817Y-469500D01*
X-663050Y-468334D01*
X-663867Y-467500D01*
X-664683Y-467167D01*
X-665733D01*
G01X-664683D02*
X-663983Y-466667D01*
X-663400Y-465834D01*
X-663167Y-464833D01*
X-663400Y-463833D01*
X-663983Y-463000D01*
X-665033Y-462500D01*
X-666083Y-462667D01*
X-667133Y-463333D01*
G01X-656000Y-462500D02*
X-656933Y-462833D01*
X-657633Y-463667D01*
X-658100Y-464667D01*
X-658450Y-466000D01*
X-658567Y-467500D01*
X-658450Y-469000D01*
X-658100Y-470333D01*
X-657633Y-471334D01*
X-656933Y-472167D01*
X-656000Y-472500D01*
X-655067Y-472167D01*
X-654367Y-471334D01*
X-653900Y-470333D01*
X-653550Y-469000D01*
X-653433Y-467500D01*
X-653550Y-466000D01*
X-653900Y-464667D01*
X-654367Y-463667D01*
X-655067Y-462833D01*
X-656000Y-462500D01*
G01X-648017Y-469167D02*
X-644983D01*
G01X-639917Y-472500D02*
X-637000Y-462500D01*
X-634083Y-472500D01*
G01X-635133Y-469000D02*
X-638867D01*
G01X-629833Y-472500D02*
Y-462500D01*
X-627033D01*
X-626100Y-463000D01*
X-625400Y-464167D01*
X-625167Y-465500D01*
X-625400Y-466833D01*
X-625983Y-467833D01*
X-627033Y-468334D01*
X-629833D01*
G01X-620333Y-472500D02*
Y-462500D01*
X-617417D01*
X-616483Y-463000D01*
X-615900Y-463667D01*
X-615667Y-465000D01*
X-615900Y-466333D01*
X-616600Y-467167D01*
X-617417Y-467667D01*
X-620333D01*
G01X-617417D02*
X-615667Y-472500D01*
G01X-610017Y-469167D02*
X-606983D01*
G01X-599000Y-472500D02*
Y-462500D01*
X-600400Y-464500D01*
G01Y-472500D02*
X-597600D01*
G01X-588100D02*
Y-462500D01*
X-592417Y-469667D01*
X-586583D01*
G54D13*
X-1649000Y-97878D03*
X-1327756Y-175039D03*
Y-167165D03*
Y-159291D03*
Y-143543D03*
Y-135669D03*
Y-127795D03*
X-1319882Y-175039D03*
Y-167165D03*
Y-159291D03*
Y-143543D03*
Y-135669D03*
Y-127795D03*
X-793728Y-138228D03*
X-457677Y-175039D03*
Y-167165D03*
Y-159291D03*
Y-143543D03*
Y-135669D03*
Y-127795D03*
X-449803Y-175039D03*
Y-167165D03*
Y-159291D03*
Y-143543D03*
Y-135669D03*
Y-127795D03*
G54D23*
G01X-1174900Y-473500D02*
X-1171300Y-466100D01*
X-1171800Y-465700D01*
X-1175900Y-473200D01*
X-1176200Y-471200D01*
X-1172500Y-465400D01*
X-1175700Y-471300D01*
X-1176500Y-469800D01*
X-1172900Y-464900D01*
X-1173600Y-451800D01*
X-1173700Y-449900D01*
X-1182100D01*
X-1187400Y-473000D01*
X-1182400D01*
X-1177800Y-456000D01*
X-1177000Y-455900D01*
X-1176100Y-468500D01*
X-1173700Y-464500D01*
X-1174600Y-450800D01*
X-1181500Y-450900D01*
X-1186400Y-472100D01*
X-1183100D01*
X-1178300Y-454800D01*
X-1176600Y-455000D01*
X-1175500Y-466300D01*
X-1174600Y-464300D01*
X-1175400Y-451700D01*
X-1181000Y-451800D01*
X-1185300Y-471300D01*
X-1183800Y-471400D01*
X-1179000Y-454300D01*
X-1176200D01*
X-1175200Y-462200D01*
X-1176200Y-452500D01*
X-1180500Y-452800D01*
X-1184300Y-470600D01*
X-1179700Y-453400D01*
X-1176800D01*
G01X-1182820Y-448900D02*
X-1188360Y-473900D01*
X-1181580D01*
X-1177300Y-456700D01*
X-1176920Y-473900D01*
X-1172260D01*
X-1163400Y-456920D01*
X-1167240Y-473900D01*
X-1160380D01*
X-1154840Y-448900D01*
X-1164540D01*
X-1172540Y-464820D01*
X-1172880Y-448900D01*
X-1182820D01*
G01X-1155800Y-449500D02*
X-1161100Y-472900D01*
X-1166100Y-473000D01*
X-1166000Y-471900D01*
X-1161800Y-472100D01*
X-1161300Y-471000D01*
X-1165900Y-471100D01*
X-1165700Y-470000D01*
X-1161300D01*
X-1160800Y-469200D01*
X-1165300Y-469100D01*
X-1165200Y-468100D01*
X-1160700D01*
X-1160400Y-467100D01*
X-1165100Y-467200D01*
X-1164900Y-466300D01*
X-1160300Y-466200D01*
X-1160000Y-465200D01*
X-1164700Y-465300D01*
X-1164400Y-464200D01*
X-1159700Y-464300D01*
X-1159300Y-463100D01*
X-1164700Y-463500D01*
X-1164000Y-462500D01*
X-1159500Y-462600D01*
X-1159000Y-461700D01*
X-1163900D01*
X-1163600Y-460600D01*
X-1159100Y-460800D01*
X-1158800Y-459900D01*
X-1163200D01*
X-1163100Y-459200D01*
X-1158800D01*
X-1158300Y-458500D01*
X-1163000Y-458400D01*
X-1162900Y-457800D01*
X-1158400Y-457900D01*
X-1158200Y-457200D01*
X-1162500Y-457000D01*
X-1163100Y-456500D01*
X-1157800D01*
X-1157500Y-455500D01*
X-1156600Y-449800D01*
X-1164000D01*
X-1164500Y-450700D01*
X-1157600D01*
X-1157800Y-451700D01*
X-1165000Y-451600D01*
X-1165400Y-452400D01*
X-1157900Y-452500D01*
X-1157800Y-453500D01*
X-1165900Y-453200D01*
X-1166200Y-453900D01*
X-1158000Y-454300D01*
X-1158300Y-455300D01*
X-1166600Y-454800D01*
X-1158900Y-455900D01*
X-1167000Y-455600D01*
X-1163500Y-456400D01*
X-1167300Y-456300D01*
X-1171700Y-465200D01*
X-1169200Y-466400D01*
X-1164500Y-457200D01*
X-1166900Y-457100D01*
X-1170600Y-465200D01*
X-1169500Y-465500D01*
X-1166000Y-457800D01*
G01X-1170300Y-466300D02*
X-1174000Y-473600D01*
G01X-1169500Y-466900D02*
X-1172800Y-473000D01*
G01X-1152800Y-456400D02*
X-1156600Y-473100D01*
X-1152200Y-473000D01*
X-1148300Y-456600D01*
X-1149500D01*
X-1152900Y-472000D01*
X-1155600Y-472300D01*
X-1152100Y-456500D01*
X-1150400Y-456400D01*
X-1153600Y-471200D01*
X-1154500Y-471400D01*
X-1151400Y-457200D01*
G01X-1153420Y-455700D02*
X-1157540Y-473900D01*
X-1151380D01*
X-1147440Y-455700D01*
X-1153420D01*
G01X-1151600Y-450100D02*
X-1146700Y-450000D01*
X-1147000Y-451000D01*
X-1151700D01*
G01X-1152020Y-448900D02*
X-1152660Y-451900D01*
X-1146380D01*
X-1145740Y-448900D01*
X-1152020D01*
G01X-1129400Y-468900D02*
X-1131800Y-471900D01*
X-1136500Y-473700D01*
X-1142100Y-473600D01*
X-1144600Y-472300D01*
X-1145800Y-471000D01*
X-1146400Y-469500D01*
X-1146700Y-467600D01*
X-1146500Y-464600D01*
X-1145400Y-461200D01*
X-1143500Y-459100D01*
X-1140200Y-456900D01*
X-1136100Y-456200D01*
X-1132300Y-456400D01*
X-1129400Y-457900D01*
X-1127500Y-460900D01*
X-1132500Y-461000D01*
X-1133400Y-459200D01*
X-1135100Y-458100D01*
X-1136800Y-458000D01*
X-1138600Y-458900D01*
X-1140300Y-460700D01*
X-1141800Y-463600D01*
X-1142400Y-466600D01*
X-1141500Y-470400D01*
X-1140200Y-471500D01*
X-1138300Y-471600D01*
X-1136300Y-471400D01*
X-1134500Y-469100D01*
X-1130300Y-469000D01*
X-1132500Y-471200D01*
X-1134900Y-472000D01*
X-1137200Y-472800D01*
X-1142300Y-472700D01*
X-1144900Y-470600D01*
X-1145800Y-467400D01*
X-1145500Y-465100D01*
X-1144700Y-462000D01*
X-1143300Y-460200D01*
X-1139800Y-457700D01*
X-1135400Y-457000D01*
X-1131300Y-457600D01*
X-1128800Y-460100D01*
X-1132100D01*
X-1134300Y-457900D01*
X-1130100Y-458800D01*
X-1129500Y-459400D01*
X-1132600Y-459000D01*
G01X-1133300Y-461900D02*
Y-461420D01*
X-1133640Y-460240D01*
X-1134300Y-459200D01*
X-1135200Y-458900D01*
X-1136580D01*
X-1138060Y-459820D01*
X-1139360Y-461000D01*
X-1140240Y-462220D01*
X-1140880Y-463920D01*
X-1141300Y-465380D01*
X-1141500Y-467060D01*
Y-468020D01*
X-1141020Y-469220D01*
X-1139780Y-470700D01*
X-1137160D01*
X-1135840Y-469500D01*
X-1134980Y-468200D01*
X-1134940Y-468100D01*
X-1128180D01*
X-1128240Y-468240D01*
X-1128840Y-469340D01*
X-1129020Y-469800D01*
X-1129740Y-470700D01*
X-1130500Y-471460D01*
X-1131660Y-472420D01*
X-1132820Y-473200D01*
X-1133740Y-473740D01*
X-1136380Y-474500D01*
X-1141640D01*
X-1142540Y-474320D01*
X-1144220Y-473760D01*
X-1144900Y-473240D01*
X-1146240Y-471900D01*
X-1146780Y-471180D01*
X-1146940Y-470880D01*
X-1147320Y-469660D01*
X-1147500Y-468640D01*
Y-464780D01*
X-1146940Y-462540D01*
X-1146380Y-461580D01*
X-1145980Y-460780D01*
X-1145420Y-459880D01*
X-1143700Y-458140D01*
X-1142740Y-457380D01*
X-1142000Y-456820D01*
X-1140240Y-456040D01*
X-1139500Y-455660D01*
X-1138800Y-455480D01*
X-1137260Y-455300D01*
X-1134320D01*
X-1132020Y-455500D01*
X-1130940Y-455860D01*
X-1130580Y-456020D01*
X-1129260Y-456780D01*
X-1128940Y-457100D01*
X-1127820Y-458420D01*
X-1127060Y-460300D01*
X-1126900Y-460800D01*
Y-461900D01*
X-1133300D01*
G01X-1137900Y-458000D02*
X-1140300Y-459100D01*
X-1142500Y-460900D01*
X-1143900Y-462600D01*
X-1144800Y-467600D01*
X-1144200Y-470000D01*
X-1141000Y-472300D01*
X-1136400Y-472200D01*
X-1131600Y-469600D01*
X-1135400Y-470400D01*
X-1141100Y-471400D01*
X-1142100Y-470700D01*
X-1142700Y-469000D01*
X-1143100Y-467100D01*
X-1142700Y-464100D01*
X-1140500Y-459900D01*
X-1143400Y-463700D01*
X-1143600Y-465700D01*
X-1143900Y-467700D01*
X-1143000Y-469900D01*
G01X-1113500Y-459200D02*
X-1123500Y-459300D01*
X-1123700Y-460100D01*
X-1114300Y-460000D01*
X-1116500Y-460800D01*
X-1124200Y-461000D01*
X-1124400Y-461900D01*
X-1117600Y-461800D01*
X-1118800Y-462800D01*
X-1124500Y-462700D01*
X-1124600Y-463600D01*
X-1119300Y-463700D01*
X-1120100Y-464800D01*
X-1125000Y-464600D01*
Y-465500D01*
X-1120600Y-465700D01*
X-1120800Y-466700D01*
X-1125300Y-466500D01*
X-1125500Y-467400D01*
X-1121000Y-467600D01*
X-1121200Y-468700D01*
X-1125600Y-468400D01*
X-1125900Y-469100D01*
X-1121500Y-469500D01*
X-1121700Y-470700D01*
X-1126100Y-470000D01*
X-1126200Y-470700D01*
X-1121900Y-471200D01*
X-1122100Y-472000D01*
X-1126300Y-471700D01*
X-1126700Y-472300D01*
X-1122100Y-472700D01*
X-1122200Y-473100D01*
X-1126800Y-473200D01*
G01X-1114060Y-460760D02*
X-1114840Y-460920D01*
X-1115740Y-461140D01*
X-1116880Y-461820D01*
X-1117700Y-462640D01*
X-1118620Y-463340D01*
X-1118840Y-464020D01*
X-1119440Y-464820D01*
X-1119660Y-465480D01*
X-1120060Y-466280D01*
X-1120280Y-466960D01*
X-1120480Y-468360D01*
X-1120680Y-468940D01*
X-1120880Y-469940D01*
X-1121080Y-470540D01*
X-1121700Y-472980D01*
X-1121820Y-473900D01*
X-1127640D01*
X-1126920Y-471060D01*
X-1126720Y-470440D01*
X-1126500Y-468800D01*
X-1126320Y-467860D01*
X-1126120Y-467260D01*
X-1125920Y-466260D01*
X-1125720Y-465660D01*
X-1125300Y-464000D01*
X-1125120Y-462220D01*
X-1124920Y-461660D01*
X-1124720Y-460660D01*
X-1124520Y-460060D01*
X-1123720Y-456800D01*
X-1123580Y-455700D01*
X-1117880D01*
X-1118100Y-456160D01*
Y-458740D01*
X-1116500Y-457160D01*
X-1115780Y-456620D01*
X-1114680Y-456060D01*
X-1113560Y-455680D01*
X-1112460Y-455500D01*
X-1111720D01*
X-1112460Y-458440D01*
X-1114060Y-460760D01*
G01X-1123100Y-456500D02*
X-1118900Y-456600D01*
X-1118800Y-457600D01*
X-1123100Y-457500D01*
X-1123300Y-458500D01*
X-1113100Y-458400D01*
X-1112600Y-456400D01*
X-1116100Y-457600D01*
X-1113500D01*
G01X-1105100Y-471100D02*
X-1104060D01*
X-1103780Y-470820D01*
X-1103200Y-470640D01*
X-1102080Y-469740D01*
X-1100800Y-468240D01*
X-1100380Y-467400D01*
X-1100180Y-467100D01*
X-1099960Y-466660D01*
X-1099540Y-465720D01*
X-1099320Y-465060D01*
X-1099100Y-464180D01*
Y-461220D01*
X-1099360Y-460200D01*
X-1099660Y-459900D01*
X-1100700Y-458640D01*
X-1101220Y-458300D01*
X-1103340D01*
X-1103700Y-458640D01*
X-1105300Y-459840D01*
X-1105760Y-460320D01*
X-1106180Y-460940D01*
X-1107060Y-462020D01*
X-1107260Y-462880D01*
X-1107660Y-463660D01*
X-1108100Y-465000D01*
Y-468640D01*
X-1107620Y-469600D01*
X-1107140Y-470340D01*
X-1105980Y-471100D01*
X-1105100D01*
G01X-1112540Y-460460D02*
X-1110680Y-458140D01*
X-1109940Y-457580D01*
X-1109000Y-456840D01*
X-1108480Y-456660D01*
X-1107940Y-456400D01*
X-1107740Y-456200D01*
X-1107480Y-456060D01*
X-1106880Y-455860D01*
X-1106480Y-455660D01*
X-1105960Y-455480D01*
X-1104600Y-455300D01*
X-1103440Y-455100D01*
X-1100940D01*
X-1098240Y-455480D01*
X-1097720Y-455660D01*
X-1097020Y-456020D01*
X-1096180Y-456640D01*
X-1095620Y-456820D01*
X-1095540Y-456900D01*
X-1094200Y-458440D01*
X-1093660Y-459520D01*
X-1093460Y-460100D01*
X-1093100Y-461020D01*
Y-464400D01*
X-1093420Y-465360D01*
X-1094300Y-465520D01*
X-1094720Y-465740D01*
X-1095320Y-465940D01*
X-1096120Y-466340D01*
X-1096720Y-466540D01*
X-1097100Y-466720D01*
X-1098100Y-466920D01*
X-1098520Y-467140D01*
X-1099160Y-467360D01*
X-1101180Y-468700D01*
X-1094660D01*
X-1095220Y-469800D01*
X-1095560Y-470320D01*
X-1097480Y-472220D01*
X-1099940Y-473740D01*
X-1102580Y-474500D01*
X-1108800D01*
X-1109300Y-474340D01*
X-1111220Y-473560D01*
X-1111720Y-473240D01*
X-1113240Y-471720D01*
X-1113560Y-471240D01*
X-1113760Y-470660D01*
X-1114140Y-469980D01*
X-1114320Y-469120D01*
X-1114500Y-468680D01*
Y-464980D01*
X-1114320Y-464260D01*
X-1114140Y-463720D01*
X-1113940Y-463320D01*
X-1113720Y-462660D01*
X-1113560Y-462000D01*
X-1111880Y-460320D01*
X-1112540Y-460460D01*
G01X-1099300Y-466400D02*
X-1093800Y-464400D01*
X-1093900Y-461100D01*
X-1094800Y-459000D01*
X-1096800Y-457300D01*
X-1100000Y-456100D01*
X-1102800Y-455900D01*
X-1106300Y-456300D01*
X-1109600Y-458100D01*
X-1111400Y-460500D01*
X-1112900Y-462600D01*
X-1113600Y-465600D01*
X-1113500Y-469100D01*
X-1112100Y-471900D01*
X-1109600Y-473300D01*
X-1105700Y-473800D01*
X-1101000Y-473400D01*
X-1098200Y-471800D01*
X-1096600Y-470100D01*
X-1096000Y-469500D01*
X-1100800Y-469700D01*
X-1102300Y-471100D01*
X-1097900Y-470400D01*
X-1100300Y-471800D01*
X-1103200Y-471400D01*
X-1100600Y-472600D01*
X-1103000D01*
X-1103700Y-471900D01*
X-1103400Y-473000D01*
X-1104600Y-471900D01*
X-1106200D01*
X-1104100Y-473100D01*
X-1107200Y-472700D01*
X-1110100Y-472100D01*
X-1111500Y-470900D01*
X-1112600Y-468600D01*
X-1112700Y-466000D01*
X-1112400Y-463700D01*
X-1111400Y-461600D01*
X-1109600Y-459500D01*
X-1108100Y-458200D01*
X-1105900Y-457200D01*
X-1102200Y-456700D01*
X-1099600Y-457300D01*
X-1097000Y-458400D01*
X-1095500Y-459500D01*
X-1094600Y-461900D01*
X-1094500Y-463900D01*
X-1098800Y-465200D01*
X-1098600Y-464000D01*
X-1095100Y-463100D01*
X-1095300Y-462000D01*
X-1098500Y-463000D01*
X-1098600Y-461700D01*
X-1095600Y-461300D01*
X-1095900Y-460200D01*
X-1098400Y-460700D01*
X-1098900Y-459900D01*
X-1096600Y-459400D01*
X-1097100Y-458900D01*
X-1099400Y-459000D01*
X-1098800Y-458500D01*
X-1100600Y-458000D01*
X-1102400Y-457400D01*
X-1104200Y-457500D01*
X-1106200Y-458100D01*
X-1107900Y-459000D01*
X-1110500Y-462200D01*
X-1111800Y-464800D01*
Y-467700D01*
X-1110700Y-470300D01*
X-1108700Y-472000D01*
X-1106600Y-471900D01*
X-1107900Y-470300D01*
X-1108900Y-468700D01*
Y-465500D01*
X-1107900Y-462300D01*
X-1106500Y-459900D01*
X-1104100Y-458200D01*
X-1108000Y-460000D01*
X-1108100Y-461500D01*
X-1108700Y-461200D01*
X-1110300Y-463600D01*
X-1111000Y-466000D01*
X-1110700Y-468100D01*
X-1109500Y-470600D01*
X-1107700Y-471400D01*
X-1109300Y-469100D01*
X-1109800Y-467600D01*
X-1108600Y-462200D01*
X-1110400Y-466800D01*
G01X-1113600Y-460900D02*
X-1112100Y-459000D01*
G01X-1093100Y-469400D02*
X-1087900Y-469700D01*
X-1086500Y-471400D01*
X-1083400Y-472300D01*
X-1081000Y-472000D01*
X-1079300Y-470600D01*
X-1079000Y-468900D01*
X-1079500Y-467700D01*
X-1080300Y-466600D01*
X-1081800Y-466000D01*
X-1083300Y-465500D01*
X-1085300Y-465000D01*
X-1087900Y-464000D01*
X-1089100Y-463200D01*
X-1089800Y-461000D01*
X-1089500Y-459000D01*
X-1088600Y-457700D01*
X-1086500Y-456700D01*
X-1084600Y-456100D01*
X-1081900Y-455900D01*
X-1079900Y-455800D01*
X-1076900Y-456300D01*
X-1075000Y-457000D01*
X-1073700Y-458000D01*
X-1073300Y-459400D01*
X-1077600Y-459500D01*
X-1078100Y-458800D01*
X-1074300Y-458500D01*
X-1074600Y-457800D01*
X-1078200Y-458200D01*
X-1076000Y-457400D01*
X-1079100Y-457700D01*
X-1077100Y-456900D01*
X-1080100Y-457300D01*
X-1079200Y-456600D01*
X-1083100Y-456800D01*
X-1080600Y-457300D01*
X-1083400Y-457700D01*
X-1083600Y-457000D01*
X-1087900Y-458400D01*
X-1084000Y-458100D01*
X-1088600Y-459100D01*
X-1088800Y-461500D01*
X-1087700Y-463600D01*
X-1084400Y-464300D01*
X-1081200Y-465400D01*
X-1078800Y-467300D01*
X-1078300Y-470500D01*
X-1079900Y-472600D01*
X-1083500Y-473300D01*
X-1085600Y-472600D01*
X-1088800Y-470500D01*
X-1092600Y-470200D01*
X-1092100Y-471800D01*
X-1091700Y-471300D01*
X-1089300Y-471500D01*
X-1091300Y-472300D01*
X-1088700Y-471600D01*
X-1084000Y-473500D01*
X-1089100D01*
X-1091000Y-472900D01*
X-1087200Y-472800D01*
X-1082700Y-473700D01*
X-1079000Y-473600D01*
X-1076500Y-472300D01*
X-1074700Y-470600D01*
X-1074300Y-467300D01*
X-1074800Y-465300D01*
X-1078800Y-463600D01*
X-1081600Y-462900D01*
X-1083400Y-462500D01*
X-1084800Y-461500D01*
X-1085000Y-458900D01*
X-1088100Y-459800D01*
X-1087200Y-462700D01*
X-1085000Y-463400D01*
X-1082000Y-464100D01*
X-1079600Y-465100D01*
X-1078200Y-466500D01*
X-1077700Y-468500D01*
X-1077500Y-470100D01*
X-1079200Y-472800D01*
X-1076800Y-471400D01*
X-1075300Y-470000D01*
X-1077300Y-470900D01*
X-1075000Y-468800D01*
X-1075200Y-466100D01*
X-1082700Y-462700D01*
X-1084200Y-462900D01*
X-1086600Y-461800D01*
X-1087200Y-460300D01*
X-1085800Y-459800D01*
X-1086600Y-461000D01*
X-1085300Y-460400D01*
X-1085600Y-461400D01*
X-1076700Y-466500D01*
X-1075900Y-467100D01*
X-1075700Y-468400D01*
X-1076800Y-469500D01*
X-1077800Y-466200D01*
X-1075900Y-468800D01*
G01X-1093780Y-468700D02*
X-1087100D01*
Y-469740D01*
X-1086800Y-470060D01*
X-1086520Y-470600D01*
X-1085820Y-470820D01*
X-1085660Y-471000D01*
X-1085120Y-471260D01*
X-1084400Y-471500D01*
X-1082360D01*
X-1080540Y-470600D01*
X-1080100Y-470140D01*
Y-469780D01*
X-1079840Y-469380D01*
X-1080380Y-467740D01*
X-1081440Y-466940D01*
X-1082560Y-466720D01*
X-1085740Y-465920D01*
X-1086940Y-465520D01*
X-1087600Y-465360D01*
X-1087740Y-465200D01*
X-1088540Y-464800D01*
X-1089140Y-464200D01*
X-1089540Y-464000D01*
X-1089800Y-463740D01*
X-1090000Y-463340D01*
X-1090180Y-463180D01*
X-1090500Y-462200D01*
Y-459800D01*
X-1090320Y-459260D01*
X-1090140Y-458500D01*
X-1090000Y-458260D01*
X-1089000Y-457260D01*
X-1088860Y-456940D01*
X-1085920Y-455480D01*
X-1083620Y-455100D01*
X-1082060Y-454900D01*
X-1080520D01*
X-1078580Y-455100D01*
X-1076240Y-455480D01*
X-1075120Y-455860D01*
X-1074800Y-456020D01*
X-1073680Y-456760D01*
X-1073160Y-457300D01*
X-1072620Y-458020D01*
X-1072500Y-458240D01*
Y-460300D01*
X-1078500D01*
Y-459200D01*
X-1079580Y-458380D01*
X-1080160Y-458100D01*
X-1082380D01*
X-1083280Y-458360D01*
X-1084020Y-458940D01*
X-1084340Y-459900D01*
X-1084060Y-460720D01*
X-1083740Y-461340D01*
X-1081860Y-462280D01*
X-1079400Y-462500D01*
X-1078660Y-462680D01*
X-1078100Y-462860D01*
X-1076500Y-463460D01*
X-1075320Y-463860D01*
X-1075060Y-464000D01*
X-1073820Y-465220D01*
X-1073480Y-466260D01*
X-1073300Y-467160D01*
Y-468420D01*
X-1073860Y-470700D01*
X-1074000Y-470960D01*
X-1075140Y-472300D01*
X-1075280Y-472440D01*
X-1076600Y-473380D01*
X-1077320Y-473740D01*
X-1079600Y-474500D01*
X-1088240D01*
X-1089160Y-474320D01*
X-1089920Y-474120D01*
X-1090860Y-473760D01*
X-1091560Y-473400D01*
X-1092700Y-472460D01*
X-1093180Y-471980D01*
X-1093340Y-471480D01*
X-1093520Y-471100D01*
X-1093700Y-470320D01*
X-1093780Y-468700D01*
G01X-1095100D02*
X-1092800D01*
G01X-1058300Y-469400D02*
X-1055400Y-467100D01*
X-1053900Y-463700D01*
X-1054400Y-461200D01*
X-1055900Y-459900D01*
X-1054800Y-463500D01*
X-1055400Y-463600D01*
X-1054600Y-464500D01*
X-1055700D01*
X-1055400Y-465300D01*
X-1056200Y-466800D01*
G01X-1059300Y-457700D02*
X-1059100Y-455600D01*
X-1055200Y-456300D01*
X-1052700Y-457900D01*
X-1051100Y-460800D01*
X-1050900Y-465200D01*
X-1052900Y-469400D01*
X-1055300Y-471900D01*
X-1059000Y-473500D01*
X-1066000D01*
X-1068000Y-471900D01*
X-1070200Y-468700D01*
X-1070600Y-464500D01*
X-1069000Y-460500D01*
X-1066000Y-457500D01*
X-1063000Y-456500D01*
X-1059200Y-456000D01*
X-1053000Y-458500D01*
X-1052000Y-461500D01*
Y-465700D01*
X-1053400Y-468600D01*
X-1055700Y-471000D01*
X-1058900Y-472600D01*
X-1063700Y-473000D01*
X-1065900Y-473600D01*
X-1068300Y-472900D01*
X-1070600Y-469300D01*
X-1065100Y-472600D01*
X-1060800Y-472200D01*
X-1057200Y-470700D01*
X-1055200Y-469100D01*
X-1053300Y-466500D01*
X-1052500Y-463400D01*
X-1052900Y-460100D01*
X-1057000Y-457400D01*
X-1058700Y-457200D01*
X-1057000Y-458500D01*
X-1055100Y-459800D01*
X-1053800Y-460900D01*
X-1053400Y-463100D01*
X-1053600Y-465600D01*
X-1054800Y-467500D01*
X-1056400Y-469200D01*
X-1058500Y-470200D01*
X-1060200Y-470700D01*
X-1061500Y-471400D01*
X-1063300Y-471600D01*
X-1065400Y-471500D01*
X-1069000Y-469300D01*
X-1069600Y-466400D01*
X-1069700Y-463700D01*
X-1068600Y-461200D01*
X-1066700Y-459200D01*
X-1063900Y-457600D01*
X-1061100Y-457000D01*
X-1059600D01*
X-1060200Y-457500D01*
X-1063300Y-458000D01*
X-1065300Y-459500D01*
X-1066900Y-460600D01*
X-1067900Y-462100D01*
X-1068800Y-464300D01*
X-1068700Y-466900D01*
X-1068200Y-469100D01*
X-1066900Y-470200D01*
X-1064300Y-470900D01*
X-1065700Y-469300D01*
X-1065800Y-465900D01*
X-1065300Y-462900D01*
X-1061200Y-458200D01*
X-1063600Y-458900D01*
X-1066400Y-461300D01*
X-1067800Y-464200D01*
Y-467200D01*
X-1067400Y-469300D01*
X-1066300Y-469700D01*
X-1067100Y-466400D01*
X-1066600Y-463400D01*
X-1064700Y-460000D01*
X-1062600Y-458800D01*
X-1065300Y-461700D01*
X-1066700Y-467400D01*
G01X-1060840Y-455100D02*
X-1057160D01*
X-1055260Y-455480D01*
X-1054740Y-455640D01*
X-1053380Y-456420D01*
X-1052660Y-456800D01*
X-1052020Y-457420D01*
X-1051820Y-458020D01*
X-1051200Y-458660D01*
X-1051000Y-459060D01*
X-1050840Y-459200D01*
X-1050700Y-459780D01*
Y-460140D01*
X-1050400Y-460460D01*
X-1050280Y-460680D01*
X-1050100Y-461740D01*
Y-464240D01*
X-1050280Y-465160D01*
X-1050480Y-465980D01*
X-1050680Y-467120D01*
X-1051220Y-468180D01*
X-1051840Y-469020D01*
X-1052040Y-469600D01*
X-1052740Y-470500D01*
X-1054480Y-472240D01*
X-1055000Y-472580D01*
X-1055420Y-472780D01*
X-1056220Y-473380D01*
X-1056920Y-473740D01*
X-1059380Y-474500D01*
X-1065600D01*
X-1067860Y-473740D01*
X-1068160Y-473600D01*
X-1069500Y-472460D01*
X-1069820Y-472120D01*
X-1070380Y-471200D01*
X-1071140Y-469860D01*
X-1071300Y-469400D01*
Y-464580D01*
X-1071120Y-463880D01*
X-1070740Y-462900D01*
X-1070540Y-462320D01*
X-1069980Y-461000D01*
X-1068840Y-459500D01*
X-1066900Y-457560D01*
X-1066180Y-457020D01*
X-1065400Y-456620D01*
X-1064440Y-456040D01*
X-1063500Y-455660D01*
X-1062940Y-455480D01*
X-1060840Y-455100D01*
G01X-1057800Y-458580D02*
X-1057000Y-459120D01*
X-1056760Y-459840D01*
X-1056340Y-460460D01*
X-1056100Y-461640D01*
Y-463760D01*
X-1056320Y-464860D01*
X-1056720Y-466060D01*
X-1056940Y-466920D01*
X-1057200Y-467460D01*
X-1057640Y-467880D01*
X-1058040Y-468480D01*
X-1059960Y-470420D01*
X-1061020Y-470840D01*
X-1061420Y-471100D01*
X-1062720D01*
X-1063340Y-470840D01*
X-1063860Y-470600D01*
X-1064360Y-470080D01*
X-1064820Y-469400D01*
X-1065100Y-468840D01*
Y-464920D01*
X-1064880Y-464120D01*
X-1064420Y-462780D01*
X-1064160Y-462520D01*
X-1063620Y-461700D01*
X-1063200Y-460840D01*
X-1062500Y-460140D01*
X-1062120Y-459860D01*
X-1061720Y-459360D01*
X-1060600Y-458580D01*
X-1060040Y-458300D01*
X-1058360D01*
X-1057800Y-458580D01*
G01X-1040300Y-459100D02*
X-1041400Y-464800D01*
G01X-1044800Y-458200D02*
X-1041400D01*
X-1044300Y-472700D01*
X-1047400Y-472300D01*
X-1044100Y-458800D01*
X-1042400Y-459100D01*
X-1045100Y-471900D01*
X-1046500D01*
X-1043400Y-459700D01*
X-1045600Y-471500D01*
G01X-1036600Y-449900D02*
X-1036800Y-451300D01*
X-1038600Y-452400D01*
X-1039800Y-456100D01*
X-1033700Y-456500D01*
X-1032300Y-452100D01*
X-1028400Y-452000D01*
X-1028900Y-455400D01*
X-1027200Y-456600D01*
X-1025900Y-456800D01*
X-1026200Y-458200D01*
X-1030000Y-458400D01*
X-1031800Y-468900D01*
X-1030400Y-471700D01*
X-1029400D01*
X-1029600Y-473300D01*
X-1033100Y-473400D01*
X-1036100Y-472800D01*
X-1036200Y-470500D01*
X-1035900Y-467100D01*
X-1034400Y-461400D01*
X-1033800Y-458800D01*
X-1033500Y-458400D01*
X-1035000Y-458200D01*
X-1039600D01*
X-1040800Y-458300D01*
X-1043600Y-473200D01*
X-1048000Y-473000D01*
X-1045100Y-459400D01*
X-1044900Y-458400D01*
X-1048700D01*
X-1048100Y-456600D01*
X-1044900Y-456400D01*
X-1045200Y-457700D01*
X-1047600Y-457500D01*
X-1026500D01*
G01X-1049580Y-459100D02*
X-1048740Y-455700D01*
X-1044900D01*
Y-454780D01*
X-1044720Y-454060D01*
X-1044340Y-452920D01*
X-1043940Y-452120D01*
X-1043740Y-451520D01*
X-1043600Y-451260D01*
X-1042340Y-450000D01*
X-1042080Y-449860D01*
X-1040580Y-449480D01*
X-1039440Y-449300D01*
X-1036140D01*
X-1035440Y-449400D01*
X-1035480Y-449540D01*
X-1035680Y-450360D01*
X-1035880Y-451280D01*
X-1036000Y-451900D01*
X-1036740D01*
X-1037060Y-452200D01*
X-1037860Y-452600D01*
X-1038220Y-452980D01*
X-1038480Y-453740D01*
X-1038960Y-455700D01*
X-1034020D01*
X-1033720Y-455080D01*
X-1033500Y-453400D01*
X-1032940Y-451100D01*
X-1027260D01*
X-1027280Y-451180D01*
X-1027480Y-452780D01*
X-1027860Y-454280D01*
X-1028100Y-454760D01*
Y-455700D01*
X-1024800D01*
X-1024880Y-455940D01*
X-1025080Y-456940D01*
X-1025280Y-457540D01*
X-1025480Y-458560D01*
X-1025620Y-459100D01*
X-1029100D01*
Y-460000D01*
X-1029280Y-460540D01*
X-1029480Y-461540D01*
X-1029680Y-462140D01*
X-1029880Y-462960D01*
X-1030100Y-464000D01*
X-1030280Y-465560D01*
X-1030480Y-466140D01*
X-1030680Y-467140D01*
X-1030880Y-467740D01*
X-1031040Y-468400D01*
X-1031300Y-468660D01*
Y-469800D01*
X-1030300Y-470560D01*
X-1029940Y-470900D01*
X-1028220D01*
X-1028680Y-472780D01*
X-1028880Y-474120D01*
Y-474140D01*
X-1030720Y-474300D01*
X-1032860D01*
X-1034380Y-474120D01*
X-1035860Y-473740D01*
X-1036640Y-473280D01*
X-1036960Y-472660D01*
X-1037100Y-472280D01*
Y-470160D01*
X-1036920Y-469260D01*
X-1036700Y-468640D01*
X-1036500Y-466840D01*
X-1036320Y-466260D01*
X-1036120Y-465260D01*
X-1035920Y-464660D01*
X-1035720Y-463660D01*
X-1035520Y-463060D01*
X-1035320Y-462060D01*
X-1035120Y-461440D01*
X-1034820Y-459100D01*
X-1039900D01*
Y-460220D01*
X-1040280Y-461780D01*
X-1040480Y-463380D01*
X-1041280Y-466540D01*
X-1041480Y-467140D01*
X-1041700Y-468200D01*
X-1041880Y-469760D01*
X-1042080Y-470340D01*
X-1042280Y-471360D01*
X-1042480Y-472140D01*
X-1042680Y-472740D01*
X-1042880Y-473740D01*
X-1042940Y-473900D01*
X-1049140D01*
X-1048300Y-470620D01*
X-1048100Y-469020D01*
X-1047920Y-468260D01*
X-1047720Y-467660D01*
X-1047520Y-466660D01*
X-1047320Y-466060D01*
X-1047120Y-465060D01*
X-1046920Y-464460D01*
X-1046700Y-463400D01*
X-1046500Y-462020D01*
X-1046140Y-460500D01*
X-1045900Y-460040D01*
Y-459100D01*
X-1049580D01*
G01X-1038400Y-451100D02*
X-1040600Y-455800D01*
X-1043300D01*
X-1041400Y-451300D01*
X-1038900Y-451000D01*
X-1041200Y-455000D01*
X-1042000Y-455100D01*
X-1040500Y-452000D01*
G01X-1037500Y-449800D02*
X-1037800Y-451000D01*
X-1038500Y-450100D01*
X-1042000Y-450700D01*
X-1043100Y-452300D01*
X-1044100Y-455100D01*
X-1044200Y-456600D01*
X-1036600Y-456800D01*
G01X-1031100Y-472500D02*
X-1031400Y-470900D01*
X-1031900Y-472200D01*
X-1035200D01*
Y-467600D01*
X-1032000Y-453700D01*
X-1030500Y-453800D01*
X-1030000Y-456700D01*
X-1033400Y-471900D01*
X-1034300Y-471600D01*
X-1034200Y-467100D01*
X-1031400Y-454500D01*
X-1030700Y-456500D01*
X-1033700Y-470600D01*
X-1032700Y-461100D01*
G01X-1032000Y-452900D02*
X-1029300D01*
X-1028000Y-457000D01*
X-1029500Y-453600D01*
X-1029100Y-457300D01*
X-1032800Y-472800D01*
X-1030200Y-472600D01*
G54D14*
X-1615984Y-178583D03*
X-1608110Y-167165D03*
X-1615984Y-162047D03*
Y-151024D03*
X-1608110Y-150630D03*
X-1615984Y-140000D03*
Y-145512D03*
X-1608110Y-134094D03*
Y-117559D03*
X-1615984Y-112441D03*
X-1608110Y-112047D03*
Y-106535D03*
Y-101024D03*
X-1615984Y-95906D03*
X-1592362Y-167165D03*
X-1600236Y-178583D03*
X-1592362Y-150630D03*
X-1600236Y-162047D03*
X-1592362Y-134094D03*
X-1600236Y-145512D03*
Y-128976D03*
X-1592362Y-117559D03*
X-1600236Y-112441D03*
X-1592362Y-101024D03*
X-1600236Y-95906D03*
X-1576614Y-167165D03*
X-1584488Y-178583D03*
X-1576614Y-150630D03*
X-1584488Y-162047D03*
X-1576614Y-134094D03*
X-1584488Y-145512D03*
Y-128976D03*
X-1576614Y-117559D03*
Y-101024D03*
X-1584488Y-112441D03*
Y-95906D03*
X-1560866Y-167165D03*
X-1568740Y-178583D03*
X-1560866Y-150630D03*
X-1568740Y-162047D03*
X-1560866Y-134094D03*
X-1568740Y-145512D03*
Y-128976D03*
X-1560866Y-117559D03*
X-1568740Y-112441D03*
X-1560866Y-101024D03*
X-1568740Y-95906D03*
X-1545118Y-167165D03*
X-1552992Y-178583D03*
X-1545118Y-150630D03*
X-1552992Y-162047D03*
X-1545118Y-134094D03*
X-1552992Y-145512D03*
Y-128976D03*
X-1545118Y-117559D03*
X-1552992Y-112441D03*
X-1545118Y-101024D03*
X-1552992Y-95906D03*
X-1189134Y-167559D03*
X-1197008Y-178976D03*
X-1189134Y-151024D03*
X-1197008Y-162441D03*
Y-145906D03*
Y-129370D03*
X-1173386Y-167559D03*
X-1181260Y-178976D03*
Y-162441D03*
Y-129370D03*
X-1157638Y-167559D03*
X-1165512Y-178976D03*
X-1157638Y-151024D03*
X-1165512Y-162441D03*
X-1157638Y-134488D03*
X-1165512Y-145906D03*
Y-129370D03*
X-1014488Y-178976D03*
Y-162441D03*
Y-145906D03*
Y-129370D03*
X-1006614Y-167559D03*
X-998740Y-178976D03*
X-1006614Y-151024D03*
X-998740Y-162441D03*
X-1006614Y-134488D03*
X-998740Y-145906D03*
Y-129370D03*
X-990866Y-167559D03*
X-982992Y-178976D03*
X-990866Y-151024D03*
X-982992Y-162441D03*
X-990866Y-134488D03*
X-982992Y-145906D03*
Y-129370D03*
X-975118Y-167559D03*
Y-151024D03*
Y-134488D03*
X-745906Y-178583D03*
Y-162047D03*
Y-151024D03*
Y-140000D03*
Y-145512D03*
Y-112441D03*
Y-95906D03*
X-738032Y-167165D03*
X-730157Y-178583D03*
X-738032Y-150630D03*
X-730157Y-162047D03*
X-738032Y-134094D03*
X-730157Y-145512D03*
Y-128976D03*
X-738032Y-117559D03*
X-730157Y-112441D03*
X-738032Y-112047D03*
Y-106535D03*
Y-101024D03*
X-730157Y-95906D03*
X-722283Y-167165D03*
X-714409Y-178583D03*
X-722283Y-150630D03*
X-714409Y-162047D03*
X-722283Y-134094D03*
X-714409Y-145512D03*
X-722283Y-117559D03*
X-714409Y-128976D03*
X-722283Y-101024D03*
X-714409Y-112441D03*
Y-95906D03*
X-706535Y-167165D03*
X-698661Y-178583D03*
X-706535Y-150630D03*
X-698661Y-162047D03*
X-706535Y-134094D03*
X-698661Y-145512D03*
X-706535Y-117559D03*
X-698661Y-128976D03*
X-706535Y-101024D03*
X-698661Y-112441D03*
Y-95906D03*
X-690787Y-167165D03*
X-682913Y-178583D03*
X-690787Y-150630D03*
X-682913Y-162047D03*
X-690787Y-134094D03*
X-682913Y-145512D03*
Y-128976D03*
X-690787Y-117559D03*
Y-101024D03*
X-682913Y-112441D03*
Y-95906D03*
X-675039Y-167165D03*
Y-150630D03*
Y-134094D03*
Y-117559D03*
Y-101024D03*
X-319055Y-167559D03*
X-326929Y-178976D03*
X-319055Y-151024D03*
X-326929Y-162441D03*
Y-145906D03*
Y-129370D03*
X-303307Y-167559D03*
X-311181Y-178976D03*
Y-162441D03*
Y-129370D03*
X-287559Y-167559D03*
X-295433Y-178976D03*
X-287559Y-151024D03*
X-295433Y-162441D03*
X-287559Y-134488D03*
X-295433Y-145906D03*
Y-129370D03*
X-144409Y-178976D03*
Y-162441D03*
Y-145906D03*
Y-129370D03*
X-136535Y-167559D03*
X-128661Y-178976D03*
X-136535Y-151024D03*
X-128661Y-162441D03*
X-136535Y-134488D03*
X-128661Y-145906D03*
Y-129370D03*
X-120787Y-167559D03*
X-112913Y-178976D03*
X-120787Y-151024D03*
X-112913Y-162441D03*
X-120787Y-134488D03*
X-112913Y-145906D03*
Y-129370D03*
X-105039Y-167559D03*
Y-151024D03*
Y-134488D03*
G54D24*
G01X-1186050Y-540000D02*
Y-552500D01*
X-1180250D01*
G01X-1174975D02*
X-1171350Y-540000D01*
X-1167725Y-552500D01*
G01X-1169030Y-548125D02*
X-1173670D01*
G01X-1159550Y-552500D02*
Y-546875D01*
X-1162450Y-540000D01*
G01X-1156650D02*
X-1159550Y-546875D01*
G01X-1144850Y-552500D02*
X-1150650D01*
Y-540000D01*
X-1144850D01*
G01X-1147170Y-546042D02*
X-1150650D01*
G01X-1138850Y-552500D02*
Y-540000D01*
X-1135225D01*
X-1134065Y-540625D01*
X-1133340Y-541458D01*
X-1133050Y-543125D01*
X-1133340Y-544792D01*
X-1134210Y-545833D01*
X-1135225Y-546458D01*
X-1138850D01*
G01X-1135225D02*
X-1133050Y-552500D01*
G01X-1112640D02*
X-1112350Y-549792D01*
X-1111915Y-547500D01*
X-1111335Y-545417D01*
X-1110610Y-543125D01*
X-1109450Y-540000D01*
X-1115250D01*
G54D15*
X-1356889Y-167165D03*
Y-118937D03*
X-1051613Y-167165D03*
Y-118937D03*
X-486810Y-167165D03*
Y-118937D03*
X-181534Y-167165D03*
Y-118937D03*
G54D25*
G01X-1652043Y-100921D02*
X-1649000Y-97878D01*
G01D02*
X-1645957Y-94835D01*
G01X-1652043D02*
X-1649000Y-97878D01*
G01D02*
X-1645957Y-100921D01*
G01X-1185925Y-592500D02*
X-1178575Y-577500D01*
G01X-1185925D02*
X-1178575Y-592500D01*
G01X-1168050D02*
X-1166825Y-592250D01*
X-1165425Y-591500D01*
X-1164550Y-590250D01*
X-1164200Y-588500D01*
X-1164550Y-586750D01*
X-1165600Y-585250D01*
X-1167175Y-584500D01*
X-1168925D01*
X-1169975Y-584000D01*
X-1170850Y-582750D01*
X-1171200Y-581000D01*
X-1170675Y-579250D01*
X-1169450Y-578000D01*
X-1168050Y-577500D01*
X-1166650Y-578000D01*
X-1165425Y-579250D01*
X-1164900Y-581000D01*
X-1165250Y-582750D01*
X-1166125Y-584000D01*
X-1167175Y-584500D01*
X-1168925D01*
X-1170500Y-585250D01*
X-1171550Y-586750D01*
X-1171900Y-588500D01*
X-1171550Y-590250D01*
X-1170675Y-591500D01*
X-1169275Y-592250D01*
X-1168050Y-592500D01*
G01X-1153850D02*
X-1152625Y-592250D01*
X-1151225Y-591500D01*
X-1150350Y-590250D01*
X-1150000Y-588500D01*
X-1150350Y-586750D01*
X-1151400Y-585250D01*
X-1152975Y-584500D01*
X-1154725D01*
X-1155775Y-584000D01*
X-1156650Y-582750D01*
X-1157000Y-581000D01*
X-1156475Y-579250D01*
X-1155250Y-578000D01*
X-1153850Y-577500D01*
X-1152450Y-578000D01*
X-1151225Y-579250D01*
X-1150700Y-581000D01*
X-1151050Y-582750D01*
X-1151925Y-584000D01*
X-1152975Y-584500D01*
X-1154725D01*
X-1156300Y-585250D01*
X-1157350Y-586750D01*
X-1157700Y-588500D01*
X-1157350Y-590250D01*
X-1156475Y-591500D01*
X-1155075Y-592250D01*
X-1153850Y-592500D01*
G01X-1140000D02*
X-1139650Y-589250D01*
X-1139125Y-586500D01*
X-1138425Y-584000D01*
X-1137550Y-581250D01*
X-1136150Y-577500D01*
X-1143150D01*
G01X-1129300Y-590250D02*
X-1128250Y-591500D01*
X-1127025Y-592250D01*
X-1125450Y-592500D01*
X-1123875Y-592000D01*
X-1122650Y-591000D01*
X-1121775Y-589250D01*
X-1121600Y-587250D01*
X-1121950Y-585250D01*
X-1122825Y-584000D01*
X-1124050Y-583000D01*
X-1125275Y-582750D01*
X-1126500Y-583000D01*
X-1128075Y-584000D01*
X-1127550Y-577500D01*
X-1122825D01*
G01X-1111600Y-592500D02*
X-1111250Y-589250D01*
X-1110725Y-586500D01*
X-1110025Y-584000D01*
X-1109150Y-581250D01*
X-1107750Y-577500D01*
X-1114750D01*
G01X-1097050Y-592500D02*
Y-577500D01*
X-1099150Y-580500D01*
G01Y-592500D02*
X-1094950D01*
G01X-1085125Y-587500D02*
X-1080575D01*
G01X-1068650Y-577500D02*
X-1070050Y-578000D01*
X-1071100Y-579250D01*
X-1071800Y-580750D01*
X-1072325Y-582750D01*
X-1072500Y-585000D01*
X-1072325Y-587250D01*
X-1071800Y-589250D01*
X-1071100Y-590750D01*
X-1070050Y-592000D01*
X-1068650Y-592500D01*
X-1067250Y-592000D01*
X-1066200Y-590750D01*
X-1065500Y-589250D01*
X-1064975Y-587250D01*
X-1064800Y-585000D01*
X-1064975Y-582750D01*
X-1065500Y-580750D01*
X-1066200Y-579250D01*
X-1067250Y-578000D01*
X-1068650Y-577500D01*
G01X-1054450D02*
X-1055850Y-578000D01*
X-1056900Y-579250D01*
X-1057600Y-580750D01*
X-1058125Y-582750D01*
X-1058300Y-585000D01*
X-1058125Y-587250D01*
X-1057600Y-589250D01*
X-1056900Y-590750D01*
X-1055850Y-592000D01*
X-1054450Y-592500D01*
X-1053050Y-592000D01*
X-1052000Y-590750D01*
X-1051300Y-589250D01*
X-1050775Y-587250D01*
X-1050600Y-585000D01*
X-1050775Y-582750D01*
X-1051300Y-580750D01*
X-1052000Y-579250D01*
X-1053050Y-578000D01*
X-1054450Y-577500D01*
G01X-1044100Y-590250D02*
X-1043050Y-591500D01*
X-1041825Y-592250D01*
X-1040250Y-592500D01*
X-1038675Y-592000D01*
X-1037450Y-591000D01*
X-1036575Y-589250D01*
X-1036400Y-587250D01*
X-1036750Y-585250D01*
X-1037625Y-584000D01*
X-1038850Y-583000D01*
X-1040075Y-582750D01*
X-1041300Y-583000D01*
X-1042875Y-584000D01*
X-1042350Y-577500D01*
X-1037625D01*
G01X-911875Y-592500D02*
X-907500Y-577500D01*
X-903125Y-592500D01*
G01X-904700Y-587250D02*
X-910300D01*
G01X-810781Y-103562D02*
X-806854Y-99635D01*
G01D02*
X-802927Y-95708D01*
G01X-810781D02*
X-806854Y-99635D01*
G01D02*
X-802927Y-103562D01*
G01X-796771Y-141271D02*
X-793728Y-138228D01*
G01D02*
X-790685Y-135185D01*
G01X-796771D02*
X-793728Y-138228D01*
G01D02*
X-790685Y-141271D01*
G01X-789127Y-103562D02*
X-785200Y-99635D01*
G01X-789127Y-95708D02*
X-785200Y-99635D01*
G01D02*
X-781273Y-103562D01*
G01X-785200Y-99635D02*
X-781273Y-95708D01*
G54D16*
X-1356889Y-145000D03*
X-1051613D03*
X-486810D03*
X-181534D03*
G54D26*
G01X-1200000Y-560000D02*
X-890000D01*
G01Y-520000D02*
X-1200000D01*
G01X-575000Y-480000D02*
X-1200000D01*
G01X-927500Y-560000D02*
Y-600000D01*
G01X-915000Y-440000D02*
Y-480000D01*
G01X-890000D02*
Y-600000D01*
G01X-870000Y-440000D02*
Y-480000D01*
G01X-680000D02*
Y-440000D01*
G01X-1200000Y-600000D02*
X-575000D01*
Y-440000D01*
X-1200000D01*
Y-600000D01*
G54D17*
X-1282480Y-172283D03*
Y-130157D03*
Y-94724D03*
Y-59291D03*
Y-23858D03*
X-1253740Y-184094D03*
X-1225394D03*
X-1207677Y-154567D03*
Y-112441D03*
Y-77008D03*
Y-41575D03*
Y-6142D03*
X-412402Y-172283D03*
Y-130157D03*
Y-94724D03*
Y-59291D03*
Y-23858D03*
X-383661Y-184094D03*
X-355315D03*
X-337598Y-154567D03*
Y-112441D03*
Y-77008D03*
Y-41575D03*
Y-6142D03*
G54D27*
G01X-1007500Y-470000D02*
X-1006450Y-475000D01*
X-1005250Y-470000D01*
X-1004050Y-475000D01*
X-1003000Y-470000D01*
G01X-1001125Y-475000D02*
X-999250Y-470000D01*
X-997375Y-475000D01*
G01X-998050Y-473250D02*
X-1000450D01*
G01X-994825Y-474333D02*
X-994225Y-474750D01*
X-993550Y-475000D01*
X-992950D01*
X-992350Y-474750D01*
X-991900Y-474333D01*
X-991675Y-473750D01*
X-991825Y-473167D01*
X-992200Y-472667D01*
X-992875Y-472333D01*
X-993775Y-472167D01*
X-994300Y-471833D01*
X-994525Y-471250D01*
X-994375Y-470667D01*
X-994000Y-470250D01*
X-993475Y-470000D01*
X-992950D01*
X-992425Y-470167D01*
X-991975Y-470583D01*
G01X-988825Y-475000D02*
Y-470000D01*
G01X-985675D02*
Y-475000D01*
G01Y-472500D02*
X-988825D01*
G01X-976525Y-474417D02*
X-976000Y-474833D01*
X-975400Y-475000D01*
X-974800Y-474833D01*
X-974275Y-474333D01*
X-973900Y-473583D01*
X-973750Y-472833D01*
Y-471917D01*
X-973900Y-471167D01*
X-974275Y-470500D01*
X-974725Y-470167D01*
X-975250Y-470000D01*
X-975850Y-470167D01*
X-976300Y-470500D01*
X-976600Y-471000D01*
X-976750Y-471667D01*
X-976600Y-472250D01*
X-976225Y-472833D01*
X-975775Y-473167D01*
X-975250Y-473250D01*
X-974650Y-473083D01*
X-974200Y-472667D01*
X-973750Y-471917D01*
G01X-969250Y-475000D02*
X-968725Y-474917D01*
X-968125Y-474667D01*
X-967750Y-474250D01*
X-967600Y-473667D01*
X-967750Y-473083D01*
X-968200Y-472583D01*
X-968875Y-472333D01*
X-969625D01*
X-970075Y-472167D01*
X-970450Y-471750D01*
X-970600Y-471167D01*
X-970375Y-470583D01*
X-969850Y-470167D01*
X-969250Y-470000D01*
X-968650Y-470167D01*
X-968125Y-470583D01*
X-967900Y-471167D01*
X-968050Y-471750D01*
X-968425Y-472167D01*
X-968875Y-472333D01*
X-969625D01*
X-970300Y-472583D01*
X-970750Y-473083D01*
X-970900Y-473667D01*
X-970750Y-474250D01*
X-970375Y-474667D01*
X-969775Y-474917D01*
X-969250Y-475000D01*
G01X-963250Y-470000D02*
X-963850Y-470167D01*
X-964300Y-470583D01*
X-964600Y-471083D01*
X-964825Y-471750D01*
X-964900Y-472500D01*
X-964825Y-473250D01*
X-964600Y-473917D01*
X-964300Y-474417D01*
X-963850Y-474833D01*
X-963250Y-475000D01*
X-962650Y-474833D01*
X-962200Y-474417D01*
X-961900Y-473917D01*
X-961675Y-473250D01*
X-961600Y-472500D01*
X-961675Y-471750D01*
X-961900Y-471083D01*
X-962200Y-470583D01*
X-962650Y-470167D01*
X-963250Y-470000D01*
G01X-958900Y-474250D02*
X-958450Y-474667D01*
X-957925Y-474917D01*
X-957250Y-475000D01*
X-956575Y-474833D01*
X-956050Y-474500D01*
X-955675Y-473917D01*
X-955600Y-473250D01*
X-955750Y-472583D01*
X-956125Y-472167D01*
X-956650Y-471833D01*
X-957175Y-471750D01*
X-957700Y-471833D01*
X-958375Y-472167D01*
X-958150Y-470000D01*
X-956125D01*
G01X-952675Y-470833D02*
X-952225Y-470333D01*
X-951700Y-470083D01*
X-951100Y-470000D01*
X-950350Y-470167D01*
X-949825Y-470583D01*
X-949675Y-471083D01*
X-949750Y-471583D01*
X-950050Y-472000D01*
X-951550Y-472833D01*
X-952225Y-473417D01*
X-952675Y-474250D01*
X-952825Y-475000D01*
X-949675D01*
G01X-946225Y-473333D02*
X-944275D01*
G01X-940675Y-472917D02*
X-940150Y-472333D01*
X-939700Y-472000D01*
X-939100Y-471833D01*
X-938575Y-472000D01*
X-938200Y-472333D01*
X-937900Y-472833D01*
X-937825Y-473417D01*
X-937900Y-473917D01*
X-938200Y-474417D01*
X-938650Y-474833D01*
X-939175Y-475000D01*
X-939775Y-474833D01*
X-940300Y-474333D01*
X-940600Y-473583D01*
X-940675Y-472750D01*
X-940525Y-471667D01*
X-940300Y-471083D01*
X-939925Y-470500D01*
X-939400Y-470083D01*
X-938875Y-470000D01*
X-938350Y-470167D01*
X-937975Y-470583D01*
G01X-934900Y-474000D02*
X-934450Y-474583D01*
X-933850Y-474917D01*
X-933175Y-475000D01*
X-932575Y-474917D01*
X-931975Y-474500D01*
X-931600Y-474000D01*
X-931525Y-473500D01*
X-931675Y-472917D01*
X-932200Y-472500D01*
X-932725Y-472333D01*
X-933400D01*
G01X-932725D02*
X-932275Y-472083D01*
X-931900Y-471667D01*
X-931750Y-471167D01*
X-931900Y-470667D01*
X-932275Y-470250D01*
X-932950Y-470000D01*
X-933625Y-470083D01*
X-934300Y-470417D01*
G01X-928525Y-474417D02*
X-928000Y-474833D01*
X-927400Y-475000D01*
X-926800Y-474833D01*
X-926275Y-474333D01*
X-925900Y-473583D01*
X-925750Y-472833D01*
Y-471917D01*
X-925900Y-471167D01*
X-926275Y-470500D01*
X-926725Y-470167D01*
X-927250Y-470000D01*
X-927850Y-470167D01*
X-928300Y-470500D01*
X-928600Y-471000D01*
X-928750Y-471667D01*
X-928600Y-472250D01*
X-928225Y-472833D01*
X-927775Y-473167D01*
X-927250Y-473250D01*
X-926650Y-473083D01*
X-926200Y-472667D01*
X-925750Y-471917D01*
G01X-922525Y-474417D02*
X-922000Y-474833D01*
X-921400Y-475000D01*
X-920800Y-474833D01*
X-920275Y-474333D01*
X-919900Y-473583D01*
X-919750Y-472833D01*
Y-471917D01*
X-919900Y-471167D01*
X-920275Y-470500D01*
X-920725Y-470167D01*
X-921250Y-470000D01*
X-921850Y-470167D01*
X-922300Y-470500D01*
X-922600Y-471000D01*
X-922750Y-471667D01*
X-922600Y-472250D01*
X-922225Y-472833D01*
X-921775Y-473167D01*
X-921250Y-473250D01*
X-920650Y-473083D01*
X-920200Y-472667D01*
X-919750Y-471917D01*
G01X-1006750Y-465000D02*
Y-460000D01*
X-1004875D01*
X-1004275Y-460250D01*
X-1003900Y-460583D01*
X-1003750Y-461250D01*
X-1003900Y-461917D01*
X-1004350Y-462333D01*
X-1004875Y-462583D01*
X-1006750D01*
G01X-1004875D02*
X-1003750Y-465000D01*
G01X-997750D02*
X-1000750D01*
Y-460000D01*
X-997750D01*
G01X-998950Y-462417D02*
X-1000750D01*
G01X-994900Y-465000D02*
Y-460000D01*
X-993400D01*
X-992800Y-460250D01*
X-992350Y-460583D01*
X-991975Y-461083D01*
X-991675Y-461667D01*
X-991600Y-462500D01*
X-991675Y-463333D01*
X-991975Y-463917D01*
X-992350Y-464417D01*
X-992800Y-464750D01*
X-993400Y-465000D01*
X-994900D01*
G01X-989200D02*
Y-460000D01*
X-987250Y-464167D01*
X-985300Y-460000D01*
Y-465000D01*
G01X-981250D02*
X-981850Y-464917D01*
X-982375Y-464583D01*
X-982825Y-464083D01*
X-983125Y-463500D01*
X-983275Y-462833D01*
Y-462167D01*
X-983125Y-461500D01*
X-982825Y-460917D01*
X-982375Y-460417D01*
X-981850Y-460083D01*
X-981250Y-460000D01*
X-980650Y-460083D01*
X-980125Y-460417D01*
X-979675Y-460917D01*
X-979375Y-461500D01*
X-979225Y-462167D01*
Y-462833D01*
X-979375Y-463500D01*
X-979675Y-464083D01*
X-980125Y-464583D01*
X-980650Y-464917D01*
X-981250Y-465000D01*
G01X-976975D02*
Y-460000D01*
X-973525Y-465000D01*
Y-460000D01*
G01X-970900Y-465000D02*
Y-460000D01*
X-969400D01*
X-968800Y-460250D01*
X-968350Y-460583D01*
X-967975Y-461083D01*
X-967675Y-461667D01*
X-967600Y-462500D01*
X-967675Y-463333D01*
X-967975Y-463917D01*
X-968350Y-464417D01*
X-968800Y-464750D01*
X-969400Y-465000D01*
X-970900D01*
G01X-1005250Y-455000D02*
Y-450000D01*
X-1006150Y-451000D01*
G01Y-455000D02*
X-1004350D01*
G01X-995200D02*
Y-450000D01*
X-993250Y-454167D01*
X-991300Y-450000D01*
Y-455000D01*
G01X-988150Y-450000D02*
X-986350D01*
G01X-987250D02*
Y-455000D01*
G01X-988150D02*
X-986350D01*
G01X-979600Y-450417D02*
X-980050Y-450167D01*
X-980575Y-450000D01*
X-981175D01*
X-981850Y-450250D01*
X-982375Y-450667D01*
X-982750Y-451167D01*
X-983050Y-452000D01*
X-983125Y-452750D01*
X-982975Y-453500D01*
X-982750Y-454000D01*
X-982300Y-454500D01*
X-981775Y-454833D01*
X-981250Y-455000D01*
X-980725D01*
X-980200Y-454833D01*
X-979750Y-454583D01*
X-979375Y-454250D01*
G01X-976750Y-455000D02*
Y-450000D01*
X-974875D01*
X-974275Y-450250D01*
X-973900Y-450583D01*
X-973750Y-451250D01*
X-973900Y-451917D01*
X-974350Y-452333D01*
X-974875Y-452583D01*
X-976750D01*
G01X-974875D02*
X-973750Y-455000D01*
G01X-969250D02*
X-969850Y-454917D01*
X-970375Y-454583D01*
X-970825Y-454083D01*
X-971125Y-453500D01*
X-971275Y-452833D01*
Y-452167D01*
X-971125Y-451500D01*
X-970825Y-450917D01*
X-970375Y-450417D01*
X-969850Y-450083D01*
X-969250Y-450000D01*
X-968650Y-450083D01*
X-968125Y-450417D01*
X-967675Y-450917D01*
X-967375Y-451500D01*
X-967225Y-452167D01*
Y-452833D01*
X-967375Y-453500D01*
X-967675Y-454083D01*
X-968125Y-454583D01*
X-968650Y-454917D01*
X-969250Y-455000D01*
G01X-964825Y-454333D02*
X-964225Y-454750D01*
X-963550Y-455000D01*
X-962950D01*
X-962350Y-454750D01*
X-961900Y-454333D01*
X-961675Y-453750D01*
X-961825Y-453167D01*
X-962200Y-452667D01*
X-962875Y-452333D01*
X-963775Y-452167D01*
X-964300Y-451833D01*
X-964525Y-451250D01*
X-964375Y-450667D01*
X-964000Y-450250D01*
X-963475Y-450000D01*
X-962950D01*
X-962425Y-450167D01*
X-961975Y-450583D01*
G01X-957250Y-455000D02*
X-957850Y-454917D01*
X-958375Y-454583D01*
X-958825Y-454083D01*
X-959125Y-453500D01*
X-959275Y-452833D01*
Y-452167D01*
X-959125Y-451500D01*
X-958825Y-450917D01*
X-958375Y-450417D01*
X-957850Y-450083D01*
X-957250Y-450000D01*
X-956650Y-450083D01*
X-956125Y-450417D01*
X-955675Y-450917D01*
X-955375Y-451500D01*
X-955225Y-452167D01*
Y-452833D01*
X-955375Y-453500D01*
X-955675Y-454083D01*
X-956125Y-454583D01*
X-956650Y-454917D01*
X-957250Y-455000D01*
G01X-952675D02*
Y-450000D01*
X-949825D01*
G01X-950875Y-452417D02*
X-952675D01*
G01X-945250Y-450000D02*
Y-455000D01*
G01X-946975Y-450000D02*
X-943525D01*
G01X-935500D02*
X-934450Y-455000D01*
X-933250Y-450000D01*
X-932050Y-455000D01*
X-931000Y-450000D01*
G01X-929125Y-455000D02*
X-927250Y-450000D01*
X-925375Y-455000D01*
G01X-926050Y-453250D02*
X-928450D01*
G01X-921250Y-455000D02*
Y-452750D01*
X-922750Y-450000D01*
G01X-919750D02*
X-921250Y-452750D01*
G54D18*
X-1141240Y-132520D03*
Y-112835D03*
Y-94331D03*
X-1132087Y-150630D03*
X-1113189D03*
X-1094291D03*
X-1085138Y-132520D03*
Y-112835D03*
Y-94331D03*
X-271161Y-132520D03*
Y-112835D03*
Y-94331D03*
X-262008Y-150630D03*
X-243110D03*
X-224213D03*
X-215059Y-132520D03*
Y-112835D03*
Y-94331D03*
G54D28*
G01X-874510Y-499000D02*
Y-493000D01*
X-871290Y-499000D01*
Y-493000D01*
G01X-867200Y-499000D02*
X-867760Y-498900D01*
X-868250Y-498500D01*
X-868670Y-497900D01*
X-868950Y-497200D01*
X-869090Y-496400D01*
Y-495600D01*
X-868950Y-494800D01*
X-868670Y-494100D01*
X-868250Y-493500D01*
X-867760Y-493100D01*
X-867200Y-493000D01*
X-866640Y-493100D01*
X-866150Y-493500D01*
X-865730Y-494100D01*
X-865450Y-494800D01*
X-865310Y-495600D01*
Y-496400D01*
X-865450Y-497200D01*
X-865730Y-497900D01*
X-866150Y-498500D01*
X-866640Y-498900D01*
X-867200Y-499000D01*
G01X-861500Y-493000D02*
Y-499000D01*
G01X-863110Y-493000D02*
X-859890D01*
G01X-856640D02*
X-854960D01*
G01X-855800D02*
Y-499000D01*
G01X-856640D02*
X-854960D01*
G01X-848560Y-493500D02*
X-848980Y-493200D01*
X-849470Y-493000D01*
X-850030D01*
X-850660Y-493300D01*
X-851150Y-493800D01*
X-851500Y-494400D01*
X-851780Y-495400D01*
X-851850Y-496300D01*
X-851710Y-497200D01*
X-851500Y-497800D01*
X-851080Y-498400D01*
X-850590Y-498800D01*
X-850100Y-499000D01*
X-849610D01*
X-849120Y-498800D01*
X-848700Y-498500D01*
X-848350Y-498100D01*
G01X-843000Y-499000D02*
X-845800D01*
Y-493000D01*
X-843000D01*
G01X-844120Y-495900D02*
X-845800D01*
G01X-833000Y-499000D02*
X-833560Y-498900D01*
X-834050Y-498500D01*
X-834470Y-497900D01*
X-834750Y-497200D01*
X-834890Y-496400D01*
Y-495600D01*
X-834750Y-494800D01*
X-834470Y-494100D01*
X-834050Y-493500D01*
X-833560Y-493100D01*
X-833000Y-493000D01*
X-832440Y-493100D01*
X-831950Y-493500D01*
X-831530Y-494100D01*
X-831250Y-494800D01*
X-831110Y-495600D01*
Y-496400D01*
X-831250Y-497200D01*
X-831530Y-497900D01*
X-831950Y-498500D01*
X-832440Y-498900D01*
X-833000Y-499000D01*
G01X-828630D02*
Y-493000D01*
X-825970D01*
G01X-826950Y-495900D02*
X-828630D01*
G01X-817300Y-499000D02*
Y-493000D01*
X-815620D01*
X-815060Y-493300D01*
X-814640Y-494000D01*
X-814500Y-494800D01*
X-814640Y-495600D01*
X-814990Y-496200D01*
X-815620Y-496500D01*
X-817300D01*
G01X-811600Y-499000D02*
Y-493000D01*
X-809850D01*
X-809290Y-493300D01*
X-808940Y-493700D01*
X-808800Y-494500D01*
X-808940Y-495300D01*
X-809360Y-495800D01*
X-809850Y-496100D01*
X-811600D01*
G01X-809850D02*
X-808800Y-499000D01*
G01X-804500D02*
X-805060Y-498900D01*
X-805550Y-498500D01*
X-805970Y-497900D01*
X-806250Y-497200D01*
X-806390Y-496400D01*
Y-495600D01*
X-806250Y-494800D01*
X-805970Y-494100D01*
X-805550Y-493500D01*
X-805060Y-493100D01*
X-804500Y-493000D01*
X-803940Y-493100D01*
X-803450Y-493500D01*
X-803030Y-494100D01*
X-802750Y-494800D01*
X-802610Y-495600D01*
Y-496400D01*
X-802750Y-497200D01*
X-803030Y-497900D01*
X-803450Y-498500D01*
X-803940Y-498900D01*
X-804500Y-499000D01*
G01X-800200D02*
Y-493000D01*
X-798520D01*
X-797960Y-493300D01*
X-797540Y-494000D01*
X-797400Y-494800D01*
X-797540Y-495600D01*
X-797890Y-496200D01*
X-798520Y-496500D01*
X-800200D01*
G01X-794500Y-499000D02*
Y-493000D01*
X-792750D01*
X-792190Y-493300D01*
X-791840Y-493700D01*
X-791700Y-494500D01*
X-791840Y-495300D01*
X-792260Y-495800D01*
X-792750Y-496100D01*
X-794500D01*
G01X-792750D02*
X-791700Y-499000D01*
G01X-788240Y-493000D02*
X-786560D01*
G01X-787400D02*
Y-499000D01*
G01X-788240D02*
X-786560D01*
G01X-780300D02*
X-783100D01*
Y-493000D01*
X-780300D01*
G01X-781420Y-495900D02*
X-783100D01*
G01X-776000Y-493000D02*
Y-499000D01*
G01X-777610Y-493000D02*
X-774390D01*
G01X-772050Y-499000D02*
X-770300Y-493000D01*
X-768550Y-499000D01*
G01X-769180Y-496900D02*
X-771420D01*
G01X-766000Y-499000D02*
Y-493000D01*
X-764250D01*
X-763690Y-493300D01*
X-763340Y-493700D01*
X-763200Y-494500D01*
X-763340Y-495300D01*
X-763760Y-495800D01*
X-764250Y-496100D01*
X-766000D01*
G01X-764250D02*
X-763200Y-499000D01*
G01X-758900D02*
Y-496300D01*
X-760300Y-493000D01*
G01X-757500D02*
X-758900Y-496300D01*
G01X-748900Y-499000D02*
Y-493000D01*
X-747220D01*
X-746660Y-493300D01*
X-746240Y-494000D01*
X-746100Y-494800D01*
X-746240Y-495600D01*
X-746590Y-496200D01*
X-747220Y-496500D01*
X-748900D01*
G01X-743200Y-499000D02*
Y-493000D01*
X-741450D01*
X-740890Y-493300D01*
X-740540Y-493700D01*
X-740400Y-494500D01*
X-740540Y-495300D01*
X-740960Y-495800D01*
X-741450Y-496100D01*
X-743200D01*
G01X-741450D02*
X-740400Y-499000D01*
G01X-736100D02*
X-736660Y-498900D01*
X-737150Y-498500D01*
X-737570Y-497900D01*
X-737850Y-497200D01*
X-737990Y-496400D01*
Y-495600D01*
X-737850Y-494800D01*
X-737570Y-494100D01*
X-737150Y-493500D01*
X-736660Y-493100D01*
X-736100Y-493000D01*
X-735540Y-493100D01*
X-735050Y-493500D01*
X-734630Y-494100D01*
X-734350Y-494800D01*
X-734210Y-495600D01*
Y-496400D01*
X-734350Y-497200D01*
X-734630Y-497900D01*
X-735050Y-498500D01*
X-735540Y-498900D01*
X-736100Y-499000D01*
G01X-731800D02*
Y-493000D01*
X-730120D01*
X-729560Y-493300D01*
X-729140Y-494000D01*
X-729000Y-494800D01*
X-729140Y-495600D01*
X-729490Y-496200D01*
X-730120Y-496500D01*
X-731800D01*
G01X-723300Y-499000D02*
X-726100D01*
Y-493000D01*
X-723300D01*
G01X-724420Y-495900D02*
X-726100D01*
G01X-720400Y-499000D02*
Y-493000D01*
X-718650D01*
X-718090Y-493300D01*
X-717740Y-493700D01*
X-717600Y-494500D01*
X-717740Y-495300D01*
X-718160Y-495800D01*
X-718650Y-496100D01*
X-720400D01*
G01X-718650D02*
X-717600Y-499000D01*
G01X-713300Y-493000D02*
Y-499000D01*
G01X-714910Y-493000D02*
X-711690D01*
G01X-707600Y-499000D02*
Y-496300D01*
X-709000Y-493000D01*
G01X-706200D02*
X-707600Y-496300D01*
G01X-701900Y-499200D02*
X-702040Y-499100D01*
Y-498900D01*
X-701900Y-498800D01*
X-701760Y-498900D01*
Y-499100D01*
X-701900Y-499200D01*
G01Y-496500D02*
X-702040Y-496400D01*
Y-496200D01*
X-701900Y-496100D01*
X-701760Y-496200D01*
Y-496400D01*
X-701900Y-496500D01*
G54D19*
X-1141240Y-142362D03*
Y-102992D03*
Y-63622D03*
Y-24252D03*
X-1128760Y-83307D03*
X-1118917Y-4567D03*
X-1107500Y-83307D03*
X-1085138Y-122677D03*
Y-83307D03*
Y-43937D03*
Y-4567D03*
X-806854Y-99635D03*
X-785200D03*
X-271161Y-142362D03*
Y-102992D03*
Y-63622D03*
Y-24252D03*
X-258681Y-83307D03*
X-237421D03*
X-248839Y-4567D03*
X-215059Y-122677D03*
Y-83307D03*
Y-43937D03*
Y-4567D03*
G54D29*
G01X-1189333Y-572500D02*
Y-565500D01*
X-1187667D01*
X-1187000Y-565850D01*
X-1186500Y-566317D01*
X-1186083Y-567017D01*
X-1185750Y-567833D01*
X-1185667Y-569000D01*
X-1185750Y-570167D01*
X-1186083Y-570983D01*
X-1186500Y-571684D01*
X-1187000Y-572150D01*
X-1187667Y-572500D01*
X-1189333D01*
G01X-1180700D02*
X-1181367Y-572383D01*
X-1181950Y-571917D01*
X-1182450Y-571217D01*
X-1182783Y-570400D01*
X-1182950Y-569467D01*
Y-568533D01*
X-1182783Y-567600D01*
X-1182450Y-566783D01*
X-1181950Y-566083D01*
X-1181367Y-565617D01*
X-1180700Y-565500D01*
X-1180033Y-565617D01*
X-1179450Y-566083D01*
X-1178950Y-566783D01*
X-1178617Y-567600D01*
X-1178450Y-568533D01*
Y-569467D01*
X-1178617Y-570400D01*
X-1178950Y-571217D01*
X-1179450Y-571917D01*
X-1180033Y-572383D01*
X-1180700Y-572500D01*
G01X-1172067Y-566083D02*
X-1172567Y-565733D01*
X-1173150Y-565500D01*
X-1173817D01*
X-1174567Y-565850D01*
X-1175150Y-566433D01*
X-1175567Y-567133D01*
X-1175900Y-568300D01*
X-1175983Y-569350D01*
X-1175817Y-570400D01*
X-1175567Y-571100D01*
X-1175067Y-571800D01*
X-1174483Y-572267D01*
X-1173900Y-572500D01*
X-1173317D01*
X-1172733Y-572267D01*
X-1172233Y-571917D01*
X-1171817Y-571450D01*
G01X-1168933Y-565500D02*
Y-570517D01*
X-1168600Y-571567D01*
X-1167933Y-572267D01*
X-1167100Y-572500D01*
X-1166267Y-572267D01*
X-1165600Y-571567D01*
X-1165267Y-570517D01*
Y-565500D01*
G01X-1162467Y-572500D02*
Y-565500D01*
X-1160300Y-571333D01*
X-1158133Y-565500D01*
Y-572500D01*
G01X-1151833D02*
X-1155167D01*
Y-565500D01*
X-1151833D01*
G01X-1153167Y-568883D02*
X-1155167D01*
G01X-1148617Y-572500D02*
Y-565500D01*
X-1144783Y-572500D01*
Y-565500D01*
G01X-1139900D02*
Y-572500D01*
G01X-1141817Y-565500D02*
X-1137983D01*
G01X-1128217Y-572500D02*
Y-565500D01*
X-1124383Y-572500D01*
Y-565500D01*
G01X-1121333D02*
Y-570517D01*
X-1121000Y-571567D01*
X-1120333Y-572267D01*
X-1119500Y-572500D01*
X-1118667Y-572267D01*
X-1118000Y-571567D01*
X-1117667Y-570517D01*
Y-565500D01*
G01X-1114867Y-572500D02*
Y-565500D01*
X-1112700Y-571333D01*
X-1110533Y-565500D01*
Y-572500D01*
G01X-1105233Y-568767D02*
X-1104900Y-568417D01*
X-1104650Y-567833D01*
X-1104483Y-567017D01*
X-1104650Y-566317D01*
X-1104983Y-565850D01*
X-1105567Y-565500D01*
X-1107817D01*
Y-572500D01*
X-1105067D01*
X-1104483Y-572033D01*
X-1104150Y-571333D01*
X-1103983Y-570517D01*
X-1104150Y-569700D01*
X-1104650Y-569000D01*
X-1105233Y-568767D01*
X-1107817D01*
G01X-1097433Y-572500D02*
X-1100767D01*
Y-565500D01*
X-1097433D01*
G01X-1098767Y-568883D02*
X-1100767D01*
G01X-1093967Y-572500D02*
Y-565500D01*
X-1091883D01*
X-1091217Y-565850D01*
X-1090800Y-566317D01*
X-1090633Y-567250D01*
X-1090800Y-568183D01*
X-1091300Y-568767D01*
X-1091883Y-569117D01*
X-1093967D01*
G01X-1091883D02*
X-1090633Y-572500D01*
G01X-1189250Y-531567D02*
X-1188583Y-532150D01*
X-1187833Y-532500D01*
X-1187167D01*
X-1186500Y-532150D01*
X-1186000Y-531567D01*
X-1185750Y-530750D01*
X-1185917Y-529933D01*
X-1186333Y-529233D01*
X-1187083Y-528767D01*
X-1188083Y-528533D01*
X-1188667Y-528067D01*
X-1188917Y-527250D01*
X-1188750Y-526433D01*
X-1188333Y-525850D01*
X-1187750Y-525500D01*
X-1187167D01*
X-1186583Y-525733D01*
X-1186083Y-526317D01*
G01X-1182450Y-532500D02*
Y-525500D01*
G01X-1178950D02*
Y-532500D01*
G01Y-529000D02*
X-1182450D01*
G01X-1172233Y-532500D02*
X-1175567D01*
Y-525500D01*
X-1172233D01*
G01X-1173567Y-528883D02*
X-1175567D01*
G01X-1165433Y-532500D02*
X-1168767D01*
Y-525500D01*
X-1165433D01*
G01X-1166767Y-528883D02*
X-1168767D01*
G01X-1160300Y-525500D02*
Y-532500D01*
G01X-1162217Y-525500D02*
X-1158383D01*
G01X-1146700D02*
Y-532500D01*
G01X-1148617Y-525500D02*
X-1144783D01*
G01X-1140900D02*
X-1138900D01*
G01X-1139900D02*
Y-532500D01*
G01X-1140900D02*
X-1138900D01*
G01X-1133100Y-525500D02*
Y-532500D01*
G01X-1135017Y-525500D02*
X-1131183D01*
G01X-1127967D02*
Y-532500D01*
X-1124633D01*
G01X-1117833D02*
X-1121167D01*
Y-525500D01*
X-1117833D01*
G01X-1119167Y-528883D02*
X-1121167D01*
G01X-1112700Y-532733D02*
X-1112867Y-532617D01*
Y-532383D01*
X-1112700Y-532267D01*
X-1112533Y-532383D01*
Y-532617D01*
X-1112700Y-532733D01*
G01Y-529584D02*
X-1112867Y-529467D01*
Y-529233D01*
X-1112700Y-529117D01*
X-1112533Y-529233D01*
Y-529467D01*
X-1112700Y-529584D01*
G01X-1187500Y-485500D02*
Y-492500D01*
G01X-1189417Y-485500D02*
X-1185583D01*
G01X-1181700D02*
X-1179700D01*
G01X-1180700D02*
Y-492500D01*
G01X-1181700D02*
X-1179700D01*
G01X-1173900Y-485500D02*
Y-492500D01*
G01X-1175817Y-485500D02*
X-1171983D01*
G01X-1168767D02*
Y-492500D01*
X-1165433D01*
G01X-1158633D02*
X-1161967D01*
Y-485500D01*
X-1158633D01*
G01X-1159967Y-488883D02*
X-1161967D01*
G01X-916667Y-570000D02*
Y-563000D01*
X-914583D01*
X-913917Y-563350D01*
X-913500Y-563817D01*
X-913333Y-564750D01*
X-913500Y-565683D01*
X-914000Y-566267D01*
X-914583Y-566617D01*
X-916667D01*
G01X-914583D02*
X-913333Y-570000D01*
G01X-906533D02*
X-909867D01*
Y-563000D01*
X-906533D01*
G01X-907867Y-566383D02*
X-909867D01*
G01X-903483Y-563000D02*
X-901400Y-570000D01*
X-899317Y-563000D01*
G01X-907850Y-451567D02*
X-907183Y-452150D01*
X-906433Y-452500D01*
X-905767D01*
X-905100Y-452150D01*
X-904600Y-451567D01*
X-904350Y-450750D01*
X-904517Y-449933D01*
X-904933Y-449233D01*
X-905683Y-448767D01*
X-906683Y-448533D01*
X-907267Y-448067D01*
X-907517Y-447250D01*
X-907350Y-446433D01*
X-906933Y-445850D01*
X-906350Y-445500D01*
X-905767D01*
X-905183Y-445733D01*
X-904683Y-446317D01*
G01X-897467Y-446083D02*
X-897967Y-445733D01*
X-898550Y-445500D01*
X-899217D01*
X-899967Y-445850D01*
X-900550Y-446433D01*
X-900967Y-447133D01*
X-901300Y-448300D01*
X-901383Y-449350D01*
X-901217Y-450400D01*
X-900967Y-451100D01*
X-900467Y-451800D01*
X-899883Y-452267D01*
X-899300Y-452500D01*
X-898717D01*
X-898133Y-452267D01*
X-897633Y-451917D01*
X-897217Y-451450D01*
G01X-894583Y-452500D02*
X-892500Y-445500D01*
X-890417Y-452500D01*
G01X-891167Y-450050D02*
X-893833D01*
G01X-887367Y-445500D02*
Y-452500D01*
X-884033D01*
G01X-877233D02*
X-880567D01*
Y-445500D01*
X-877233D01*
G01X-878567Y-448883D02*
X-880567D01*
G01X-874333Y-572500D02*
Y-565500D01*
X-872667D01*
X-872000Y-565850D01*
X-871500Y-566317D01*
X-871083Y-567017D01*
X-870750Y-567833D01*
X-870667Y-569000D01*
X-870750Y-570167D01*
X-871083Y-570983D01*
X-871500Y-571684D01*
X-872000Y-572150D01*
X-872667Y-572500D01*
X-874333D01*
G01X-866700Y-565500D02*
X-864700D01*
G01X-865700D02*
Y-572500D01*
G01X-866700D02*
X-864700D01*
G01X-860650Y-571567D02*
X-859983Y-572150D01*
X-859233Y-572500D01*
X-858567D01*
X-857900Y-572150D01*
X-857400Y-571567D01*
X-857150Y-570750D01*
X-857317Y-569933D01*
X-857733Y-569233D01*
X-858483Y-568767D01*
X-859483Y-568533D01*
X-860067Y-568067D01*
X-860317Y-567250D01*
X-860150Y-566433D01*
X-859733Y-565850D01*
X-859150Y-565500D01*
X-858567D01*
X-857983Y-565733D01*
X-857483Y-566317D01*
G01X-850267Y-566083D02*
X-850767Y-565733D01*
X-851350Y-565500D01*
X-852017D01*
X-852767Y-565850D01*
X-853350Y-566433D01*
X-853767Y-567133D01*
X-854100Y-568300D01*
X-854183Y-569350D01*
X-854017Y-570400D01*
X-853767Y-571100D01*
X-853267Y-571800D01*
X-852683Y-572267D01*
X-852100Y-572500D01*
X-851517D01*
X-850933Y-572267D01*
X-850433Y-571917D01*
X-850017Y-571450D01*
G01X-846967Y-565500D02*
Y-572500D01*
X-843633D01*
G01X-838500D02*
X-839167Y-572383D01*
X-839750Y-571917D01*
X-840250Y-571217D01*
X-840583Y-570400D01*
X-840750Y-569467D01*
Y-568533D01*
X-840583Y-567600D01*
X-840250Y-566783D01*
X-839750Y-566083D01*
X-839167Y-565617D01*
X-838500Y-565500D01*
X-837833Y-565617D01*
X-837250Y-566083D01*
X-836750Y-566783D01*
X-836417Y-567600D01*
X-836250Y-568533D01*
Y-569467D01*
X-836417Y-570400D01*
X-836750Y-571217D01*
X-837250Y-571917D01*
X-837833Y-572383D01*
X-838500Y-572500D01*
G01X-833450Y-571567D02*
X-832783Y-572150D01*
X-832033Y-572500D01*
X-831367D01*
X-830700Y-572150D01*
X-830200Y-571567D01*
X-829950Y-570750D01*
X-830117Y-569933D01*
X-830533Y-569233D01*
X-831283Y-568767D01*
X-832283Y-568533D01*
X-832867Y-568067D01*
X-833117Y-567250D01*
X-832950Y-566433D01*
X-832533Y-565850D01*
X-831950Y-565500D01*
X-831367D01*
X-830783Y-565733D01*
X-830283Y-566317D01*
G01X-823233Y-572500D02*
X-826567D01*
Y-565500D01*
X-823233D01*
G01X-824567Y-568883D02*
X-826567D01*
G01X-819933Y-572500D02*
Y-565500D01*
X-818267D01*
X-817600Y-565850D01*
X-817100Y-566317D01*
X-816683Y-567017D01*
X-816350Y-567833D01*
X-816267Y-569000D01*
X-816350Y-570167D01*
X-816683Y-570983D01*
X-817100Y-571684D01*
X-817600Y-572150D01*
X-818267Y-572500D01*
X-819933D01*
G01X-807000Y-565500D02*
X-805833Y-572500D01*
X-804500Y-565500D01*
X-803167Y-572500D01*
X-802000Y-565500D01*
G01X-798700D02*
X-796700D01*
G01X-797700D02*
Y-572500D01*
G01X-798700D02*
X-796700D01*
G01X-790900Y-565500D02*
Y-572500D01*
G01X-792817Y-565500D02*
X-788983D01*
G01X-785850Y-572500D02*
Y-565500D01*
G01X-782350D02*
Y-572500D01*
G01Y-569000D02*
X-785850D01*
G01X-777300Y-572500D02*
X-777967Y-572383D01*
X-778550Y-571917D01*
X-779050Y-571217D01*
X-779383Y-570400D01*
X-779550Y-569467D01*
Y-568533D01*
X-779383Y-567600D01*
X-779050Y-566783D01*
X-778550Y-566083D01*
X-777967Y-565617D01*
X-777300Y-565500D01*
X-776633Y-565617D01*
X-776050Y-566083D01*
X-775550Y-566783D01*
X-775217Y-567600D01*
X-775050Y-568533D01*
Y-569467D01*
X-775217Y-570400D01*
X-775550Y-571217D01*
X-776050Y-571917D01*
X-776633Y-572383D01*
X-777300Y-572500D01*
G01X-772333Y-565500D02*
Y-570517D01*
X-772000Y-571567D01*
X-771333Y-572267D01*
X-770500Y-572500D01*
X-769667Y-572267D01*
X-769000Y-571567D01*
X-768667Y-570517D01*
Y-565500D01*
G01X-763700D02*
Y-572500D01*
G01X-765617Y-565500D02*
X-761783D01*
G01X-750100D02*
Y-572500D01*
G01X-752017Y-565500D02*
X-748183D01*
G01X-745050Y-572500D02*
Y-565500D01*
G01X-741550D02*
Y-572500D01*
G01Y-569000D02*
X-745050D01*
G01X-734833Y-572500D02*
X-738167D01*
Y-565500D01*
X-734833D01*
G01X-736167Y-568883D02*
X-738167D01*
G01X-724567Y-572500D02*
Y-565500D01*
X-722567D01*
X-721900Y-565850D01*
X-721400Y-566667D01*
X-721233Y-567600D01*
X-721400Y-568533D01*
X-721817Y-569233D01*
X-722567Y-569584D01*
X-724567D01*
G01X-717767Y-572500D02*
Y-565500D01*
X-715683D01*
X-715017Y-565850D01*
X-714600Y-566317D01*
X-714433Y-567250D01*
X-714600Y-568183D01*
X-715100Y-568767D01*
X-715683Y-569117D01*
X-717767D01*
G01X-715683D02*
X-714433Y-572500D01*
G01X-710300Y-565500D02*
X-708300D01*
G01X-709300D02*
Y-572500D01*
G01X-710300D02*
X-708300D01*
G01X-702500D02*
X-703167Y-572383D01*
X-703750Y-571917D01*
X-704250Y-571217D01*
X-704583Y-570400D01*
X-704750Y-569467D01*
Y-568533D01*
X-704583Y-567600D01*
X-704250Y-566783D01*
X-703750Y-566083D01*
X-703167Y-565617D01*
X-702500Y-565500D01*
X-701833Y-565617D01*
X-701250Y-566083D01*
X-700750Y-566783D01*
X-700417Y-567600D01*
X-700250Y-568533D01*
Y-569467D01*
X-700417Y-570400D01*
X-700750Y-571217D01*
X-701250Y-571917D01*
X-701833Y-572383D01*
X-702500Y-572500D01*
G01X-697367D02*
Y-565500D01*
X-695283D01*
X-694617Y-565850D01*
X-694200Y-566317D01*
X-694033Y-567250D01*
X-694200Y-568183D01*
X-694700Y-568767D01*
X-695283Y-569117D01*
X-697367D01*
G01X-695283D02*
X-694033Y-572500D01*
G01X-684600Y-565500D02*
X-683433Y-572500D01*
X-682100Y-565500D01*
X-680767Y-572500D01*
X-679600Y-565500D01*
G01X-676967Y-572500D02*
Y-565500D01*
X-674883D01*
X-674217Y-565850D01*
X-673800Y-566317D01*
X-673633Y-567250D01*
X-673800Y-568183D01*
X-674300Y-568767D01*
X-674883Y-569117D01*
X-676967D01*
G01X-674883D02*
X-673633Y-572500D01*
G01X-669500Y-565500D02*
X-667500D01*
G01X-668500D02*
Y-572500D01*
G01X-669500D02*
X-667500D01*
G01X-661700Y-565500D02*
Y-572500D01*
G01X-663617Y-565500D02*
X-659783D01*
G01X-654900D02*
Y-572500D01*
G01X-656817Y-565500D02*
X-652983D01*
G01X-646433Y-572500D02*
X-649767D01*
Y-565500D01*
X-646433D01*
G01X-647767Y-568883D02*
X-649767D01*
G01X-643217Y-572500D02*
Y-565500D01*
X-639383Y-572500D01*
Y-565500D01*
G01X-625867Y-566083D02*
X-626367Y-565733D01*
X-626950Y-565500D01*
X-627617D01*
X-628367Y-565850D01*
X-628950Y-566433D01*
X-629367Y-567133D01*
X-629700Y-568300D01*
X-629783Y-569350D01*
X-629617Y-570400D01*
X-629367Y-571100D01*
X-628867Y-571800D01*
X-628283Y-572267D01*
X-627700Y-572500D01*
X-627117D01*
X-626533Y-572267D01*
X-626033Y-571917D01*
X-625617Y-571450D01*
G01X-620900Y-572500D02*
X-621567Y-572383D01*
X-622150Y-571917D01*
X-622650Y-571217D01*
X-622983Y-570400D01*
X-623150Y-569467D01*
Y-568533D01*
X-622983Y-567600D01*
X-622650Y-566783D01*
X-622150Y-566083D01*
X-621567Y-565617D01*
X-620900Y-565500D01*
X-620233Y-565617D01*
X-619650Y-566083D01*
X-619150Y-566783D01*
X-618817Y-567600D01*
X-618650Y-568533D01*
Y-569467D01*
X-618817Y-570400D01*
X-619150Y-571217D01*
X-619650Y-571917D01*
X-620233Y-572383D01*
X-620900Y-572500D01*
G01X-616017D02*
Y-565500D01*
X-612183Y-572500D01*
Y-565500D01*
G01X-609050Y-571567D02*
X-608383Y-572150D01*
X-607633Y-572500D01*
X-606967D01*
X-606300Y-572150D01*
X-605800Y-571567D01*
X-605550Y-570750D01*
X-605717Y-569933D01*
X-606133Y-569233D01*
X-606883Y-568767D01*
X-607883Y-568533D01*
X-608467Y-568067D01*
X-608717Y-567250D01*
X-608550Y-566433D01*
X-608133Y-565850D01*
X-607550Y-565500D01*
X-606967D01*
X-606383Y-565733D01*
X-605883Y-566317D01*
G01X-598833Y-572500D02*
X-602167D01*
Y-565500D01*
X-598833D01*
G01X-600167Y-568883D02*
X-602167D01*
G01X-595617Y-572500D02*
Y-565500D01*
X-591783Y-572500D01*
Y-565500D01*
G01X-586900D02*
Y-572500D01*
G01X-588817Y-565500D02*
X-584983D01*
G01X-872500Y-587500D02*
X-873167Y-587383D01*
X-873750Y-586917D01*
X-874250Y-586217D01*
X-874583Y-585400D01*
X-874750Y-584467D01*
Y-583533D01*
X-874583Y-582600D01*
X-874250Y-581783D01*
X-873750Y-581083D01*
X-873167Y-580617D01*
X-872500Y-580500D01*
X-871833Y-580617D01*
X-871250Y-581083D01*
X-870750Y-581783D01*
X-870417Y-582600D01*
X-870250Y-583533D01*
Y-584467D01*
X-870417Y-585400D01*
X-870750Y-586217D01*
X-871250Y-586917D01*
X-871833Y-587383D01*
X-872500Y-587500D01*
G01X-867283D02*
Y-580500D01*
X-864117D01*
G01X-865283Y-583883D02*
X-867283D01*
G01X-854267Y-587500D02*
Y-580500D01*
X-852100Y-586333D01*
X-849933Y-580500D01*
Y-587500D01*
G01X-846300Y-580500D02*
X-844300D01*
G01X-845300D02*
Y-587500D01*
G01X-846300D02*
X-844300D01*
G01X-836667Y-581083D02*
X-837167Y-580733D01*
X-837750Y-580500D01*
X-838417D01*
X-839167Y-580850D01*
X-839750Y-581433D01*
X-840167Y-582133D01*
X-840500Y-583300D01*
X-840583Y-584350D01*
X-840417Y-585400D01*
X-840167Y-586100D01*
X-839667Y-586800D01*
X-839083Y-587267D01*
X-838500Y-587500D01*
X-837917D01*
X-837333Y-587267D01*
X-836833Y-586917D01*
X-836417Y-586450D01*
G01X-833367Y-587500D02*
Y-580500D01*
X-831283D01*
X-830617Y-580850D01*
X-830200Y-581317D01*
X-830033Y-582250D01*
X-830200Y-583183D01*
X-830700Y-583767D01*
X-831283Y-584117D01*
X-833367D01*
G01X-831283D02*
X-830033Y-587500D01*
G01X-824900D02*
X-825567Y-587383D01*
X-826150Y-586917D01*
X-826650Y-586217D01*
X-826983Y-585400D01*
X-827150Y-584467D01*
Y-583533D01*
X-826983Y-582600D01*
X-826650Y-581783D01*
X-826150Y-581083D01*
X-825567Y-580617D01*
X-824900Y-580500D01*
X-824233Y-580617D01*
X-823650Y-581083D01*
X-823150Y-581783D01*
X-822817Y-582600D01*
X-822650Y-583533D01*
Y-584467D01*
X-822817Y-585400D01*
X-823150Y-586217D01*
X-823650Y-586917D01*
X-824233Y-587383D01*
X-824900Y-587500D01*
G01X-819850Y-586567D02*
X-819183Y-587150D01*
X-818433Y-587500D01*
X-817767D01*
X-817100Y-587150D01*
X-816600Y-586567D01*
X-816350Y-585750D01*
X-816517Y-584933D01*
X-816933Y-584233D01*
X-817683Y-583767D01*
X-818683Y-583533D01*
X-819267Y-583067D01*
X-819517Y-582250D01*
X-819350Y-581433D01*
X-818933Y-580850D01*
X-818350Y-580500D01*
X-817767D01*
X-817183Y-580733D01*
X-816683Y-581317D01*
G01X-811300Y-587500D02*
X-811967Y-587383D01*
X-812550Y-586917D01*
X-813050Y-586217D01*
X-813383Y-585400D01*
X-813550Y-584467D01*
Y-583533D01*
X-813383Y-582600D01*
X-813050Y-581783D01*
X-812550Y-581083D01*
X-811967Y-580617D01*
X-811300Y-580500D01*
X-810633Y-580617D01*
X-810050Y-581083D01*
X-809550Y-581783D01*
X-809217Y-582600D01*
X-809050Y-583533D01*
Y-584467D01*
X-809217Y-585400D01*
X-809550Y-586217D01*
X-810050Y-586917D01*
X-810633Y-587383D01*
X-811300Y-587500D01*
G01X-806083D02*
Y-580500D01*
X-802917D01*
G01X-804083Y-583883D02*
X-806083D01*
G01X-797700Y-580500D02*
Y-587500D01*
G01X-799617Y-580500D02*
X-795783D01*
G01X-782267Y-581083D02*
X-782767Y-580733D01*
X-783350Y-580500D01*
X-784017D01*
X-784767Y-580850D01*
X-785350Y-581433D01*
X-785767Y-582133D01*
X-786100Y-583300D01*
X-786183Y-584350D01*
X-786017Y-585400D01*
X-785767Y-586100D01*
X-785267Y-586800D01*
X-784683Y-587267D01*
X-784100Y-587500D01*
X-783517D01*
X-782933Y-587267D01*
X-782433Y-586917D01*
X-782017Y-586450D01*
G01X-777300Y-587500D02*
X-777967Y-587383D01*
X-778550Y-586917D01*
X-779050Y-586217D01*
X-779383Y-585400D01*
X-779550Y-584467D01*
Y-583533D01*
X-779383Y-582600D01*
X-779050Y-581783D01*
X-778550Y-581083D01*
X-777967Y-580617D01*
X-777300Y-580500D01*
X-776633Y-580617D01*
X-776050Y-581083D01*
X-775550Y-581783D01*
X-775217Y-582600D01*
X-775050Y-583533D01*
Y-584467D01*
X-775217Y-585400D01*
X-775550Y-586217D01*
X-776050Y-586917D01*
X-776633Y-587383D01*
X-777300Y-587500D01*
G01X-772167D02*
Y-580500D01*
X-770083D01*
X-769417Y-580850D01*
X-769000Y-581317D01*
X-768833Y-582250D01*
X-769000Y-583183D01*
X-769500Y-583767D01*
X-770083Y-584117D01*
X-772167D01*
G01X-770083D02*
X-768833Y-587500D01*
G01X-765367D02*
Y-580500D01*
X-763367D01*
X-762700Y-580850D01*
X-762200Y-581667D01*
X-762033Y-582600D01*
X-762200Y-583533D01*
X-762617Y-584233D01*
X-763367Y-584584D01*
X-765367D01*
G01X-756900Y-587500D02*
X-757567Y-587383D01*
X-758150Y-586917D01*
X-758650Y-586217D01*
X-758983Y-585400D01*
X-759150Y-584467D01*
Y-583533D01*
X-758983Y-582600D01*
X-758650Y-581783D01*
X-758150Y-581083D01*
X-757567Y-580617D01*
X-756900Y-580500D01*
X-756233Y-580617D01*
X-755650Y-581083D01*
X-755150Y-581783D01*
X-754817Y-582600D01*
X-754650Y-583533D01*
Y-584467D01*
X-754817Y-585400D01*
X-755150Y-586217D01*
X-755650Y-586917D01*
X-756233Y-587383D01*
X-756900Y-587500D01*
G01X-751767D02*
Y-580500D01*
X-749683D01*
X-749017Y-580850D01*
X-748600Y-581317D01*
X-748433Y-582250D01*
X-748600Y-583183D01*
X-749100Y-583767D01*
X-749683Y-584117D01*
X-751767D01*
G01X-749683D02*
X-748433Y-587500D01*
G01X-745383D02*
X-743300Y-580500D01*
X-741217Y-587500D01*
G01X-741967Y-585050D02*
X-744633D01*
G01X-736500Y-580500D02*
Y-587500D01*
G01X-738417Y-580500D02*
X-734583D01*
G01X-730700D02*
X-728700D01*
G01X-729700D02*
Y-587500D01*
G01X-730700D02*
X-728700D01*
G01X-722900D02*
X-723567Y-587383D01*
X-724150Y-586917D01*
X-724650Y-586217D01*
X-724983Y-585400D01*
X-725150Y-584467D01*
Y-583533D01*
X-724983Y-582600D01*
X-724650Y-581783D01*
X-724150Y-581083D01*
X-723567Y-580617D01*
X-722900Y-580500D01*
X-722233Y-580617D01*
X-721650Y-581083D01*
X-721150Y-581783D01*
X-720817Y-582600D01*
X-720650Y-583533D01*
Y-584467D01*
X-720817Y-585400D01*
X-721150Y-586217D01*
X-721650Y-586917D01*
X-722233Y-587383D01*
X-722900Y-587500D01*
G01X-718017D02*
Y-580500D01*
X-714183Y-587500D01*
Y-580500D01*
G01X-709300Y-587733D02*
X-709467Y-587617D01*
Y-587383D01*
X-709300Y-587267D01*
X-709133Y-587383D01*
Y-587617D01*
X-709300Y-587733D01*
G01X-870667Y-551083D02*
X-871167Y-550733D01*
X-871750Y-550500D01*
X-872417D01*
X-873167Y-550850D01*
X-873750Y-551433D01*
X-874167Y-552133D01*
X-874500Y-553300D01*
X-874583Y-554350D01*
X-874417Y-555400D01*
X-874167Y-556100D01*
X-873667Y-556800D01*
X-873083Y-557267D01*
X-872500Y-557500D01*
X-871917D01*
X-871333Y-557267D01*
X-870833Y-556917D01*
X-870417Y-556450D01*
G01X-865700Y-557500D02*
X-866367Y-557383D01*
X-866950Y-556917D01*
X-867450Y-556217D01*
X-867783Y-555400D01*
X-867950Y-554467D01*
Y-553533D01*
X-867783Y-552600D01*
X-867450Y-551783D01*
X-866950Y-551083D01*
X-866367Y-550617D01*
X-865700Y-550500D01*
X-865033Y-550617D01*
X-864450Y-551083D01*
X-863950Y-551783D01*
X-863617Y-552600D01*
X-863450Y-553533D01*
Y-554467D01*
X-863617Y-555400D01*
X-863950Y-556217D01*
X-864450Y-556917D01*
X-865033Y-557383D01*
X-865700Y-557500D01*
G01X-860817D02*
Y-550500D01*
X-856983Y-557500D01*
Y-550500D01*
G01X-853683Y-557500D02*
Y-550500D01*
X-850517D01*
G01X-851683Y-553883D02*
X-853683D01*
G01X-846300Y-550500D02*
X-844300D01*
G01X-845300D02*
Y-557500D01*
G01X-846300D02*
X-844300D01*
G01X-840333D02*
Y-550500D01*
X-838667D01*
X-838000Y-550850D01*
X-837500Y-551317D01*
X-837083Y-552017D01*
X-836750Y-552833D01*
X-836667Y-554000D01*
X-836750Y-555167D01*
X-837083Y-555983D01*
X-837500Y-556684D01*
X-838000Y-557150D01*
X-838667Y-557500D01*
X-840333D01*
G01X-830033D02*
X-833367D01*
Y-550500D01*
X-830033D01*
G01X-831367Y-553883D02*
X-833367D01*
G01X-826817Y-557500D02*
Y-550500D01*
X-822983Y-557500D01*
Y-550500D01*
G01X-816267Y-551083D02*
X-816767Y-550733D01*
X-817350Y-550500D01*
X-818017D01*
X-818767Y-550850D01*
X-819350Y-551433D01*
X-819767Y-552133D01*
X-820100Y-553300D01*
X-820183Y-554350D01*
X-820017Y-555400D01*
X-819767Y-556100D01*
X-819267Y-556800D01*
X-818683Y-557267D01*
X-818100Y-557500D01*
X-817517D01*
X-816933Y-557267D01*
X-816433Y-556917D01*
X-816017Y-556450D01*
G01X-809633Y-557500D02*
X-812967D01*
Y-550500D01*
X-809633D01*
G01X-810967Y-553883D02*
X-812967D01*
G01X-799783Y-557500D02*
X-797700Y-550500D01*
X-795617Y-557500D01*
G01X-796367Y-555050D02*
X-799033D01*
G01X-792817Y-557500D02*
Y-550500D01*
X-788983Y-557500D01*
Y-550500D01*
G01X-785933Y-557500D02*
Y-550500D01*
X-784267D01*
X-783600Y-550850D01*
X-783100Y-551317D01*
X-782683Y-552017D01*
X-782350Y-552833D01*
X-782267Y-554000D01*
X-782350Y-555167D01*
X-782683Y-555983D01*
X-783100Y-556684D01*
X-783600Y-557150D01*
X-784267Y-557500D01*
X-785933D01*
G01X-771500Y-550500D02*
X-769500D01*
G01X-770500D02*
Y-557500D01*
G01X-771500D02*
X-769500D01*
G01X-763700Y-550500D02*
Y-557500D01*
G01X-765617Y-550500D02*
X-761783D01*
G01X-758650Y-556567D02*
X-757983Y-557150D01*
X-757233Y-557500D01*
X-756567D01*
X-755900Y-557150D01*
X-755400Y-556567D01*
X-755150Y-555750D01*
X-755317Y-554933D01*
X-755733Y-554233D01*
X-756483Y-553767D01*
X-757483Y-553533D01*
X-758067Y-553067D01*
X-758317Y-552250D01*
X-758150Y-551433D01*
X-757733Y-550850D01*
X-757150Y-550500D01*
X-756567D01*
X-755983Y-550733D01*
X-755483Y-551317D01*
G01X-741467Y-551083D02*
X-741967Y-550733D01*
X-742550Y-550500D01*
X-743217D01*
X-743967Y-550850D01*
X-744550Y-551433D01*
X-744967Y-552133D01*
X-745300Y-553300D01*
X-745383Y-554350D01*
X-745217Y-555400D01*
X-744967Y-556100D01*
X-744467Y-556800D01*
X-743883Y-557267D01*
X-743300Y-557500D01*
X-742717D01*
X-742133Y-557267D01*
X-741633Y-556917D01*
X-741217Y-556450D01*
G01X-736500Y-557500D02*
X-737167Y-557383D01*
X-737750Y-556917D01*
X-738250Y-556217D01*
X-738583Y-555400D01*
X-738750Y-554467D01*
Y-553533D01*
X-738583Y-552600D01*
X-738250Y-551783D01*
X-737750Y-551083D01*
X-737167Y-550617D01*
X-736500Y-550500D01*
X-735833Y-550617D01*
X-735250Y-551083D01*
X-734750Y-551783D01*
X-734417Y-552600D01*
X-734250Y-553533D01*
Y-554467D01*
X-734417Y-555400D01*
X-734750Y-556217D01*
X-735250Y-556917D01*
X-735833Y-557383D01*
X-736500Y-557500D01*
G01X-731617D02*
Y-550500D01*
X-727783Y-557500D01*
Y-550500D01*
G01X-722900D02*
Y-557500D01*
G01X-724817Y-550500D02*
X-720983D01*
G01X-714433Y-557500D02*
X-717767D01*
Y-550500D01*
X-714433D01*
G01X-715767Y-553883D02*
X-717767D01*
G01X-711217Y-557500D02*
Y-550500D01*
X-707383Y-557500D01*
Y-550500D01*
G01X-702500D02*
Y-557500D01*
G01X-704417Y-550500D02*
X-700583D01*
G01X-697450Y-556567D02*
X-696783Y-557150D01*
X-696033Y-557500D01*
X-695367D01*
X-694700Y-557150D01*
X-694200Y-556567D01*
X-693950Y-555750D01*
X-694117Y-554933D01*
X-694533Y-554233D01*
X-695283Y-553767D01*
X-696283Y-553533D01*
X-696867Y-553067D01*
X-697117Y-552250D01*
X-696950Y-551433D01*
X-696533Y-550850D01*
X-695950Y-550500D01*
X-695367D01*
X-694783Y-550733D01*
X-694283Y-551317D01*
G01X-684267Y-557500D02*
Y-550500D01*
X-682100Y-556333D01*
X-679933Y-550500D01*
Y-557500D01*
G01X-677383D02*
X-675300Y-550500D01*
X-673217Y-557500D01*
G01X-673967Y-555050D02*
X-676633D01*
G01X-668500Y-557500D02*
Y-554350D01*
X-670167Y-550500D01*
G01X-666833D02*
X-668500Y-554350D01*
G01X-656817Y-557500D02*
Y-550500D01*
X-652983Y-557500D01*
Y-550500D01*
G01X-648100Y-557500D02*
X-648767Y-557383D01*
X-649350Y-556917D01*
X-649850Y-556217D01*
X-650183Y-555400D01*
X-650350Y-554467D01*
Y-553533D01*
X-650183Y-552600D01*
X-649850Y-551783D01*
X-649350Y-551083D01*
X-648767Y-550617D01*
X-648100Y-550500D01*
X-647433Y-550617D01*
X-646850Y-551083D01*
X-646350Y-551783D01*
X-646017Y-552600D01*
X-645850Y-553533D01*
Y-554467D01*
X-646017Y-555400D01*
X-646350Y-556217D01*
X-646850Y-556917D01*
X-647433Y-557383D01*
X-648100Y-557500D01*
G01X-641300Y-550500D02*
Y-557500D01*
G01X-643217Y-550500D02*
X-639383D01*
G01X-627033Y-553767D02*
X-626700Y-553417D01*
X-626450Y-552833D01*
X-626283Y-552017D01*
X-626450Y-551317D01*
X-626783Y-550850D01*
X-627367Y-550500D01*
X-629617D01*
Y-557500D01*
X-626867D01*
X-626283Y-557033D01*
X-625950Y-556333D01*
X-625783Y-555517D01*
X-625950Y-554700D01*
X-626450Y-554000D01*
X-627033Y-553767D01*
X-629617D01*
G01X-619233Y-557500D02*
X-622567D01*
Y-550500D01*
X-619233D01*
G01X-620567Y-553883D02*
X-622567D01*
G01X-870667Y-536083D02*
X-871167Y-535733D01*
X-871750Y-535500D01*
X-872417D01*
X-873167Y-535850D01*
X-873750Y-536433D01*
X-874167Y-537133D01*
X-874500Y-538300D01*
X-874583Y-539350D01*
X-874417Y-540400D01*
X-874167Y-541100D01*
X-873667Y-541800D01*
X-873083Y-542267D01*
X-872500Y-542500D01*
X-871917D01*
X-871333Y-542267D01*
X-870833Y-541917D01*
X-870417Y-541450D01*
G01X-865700Y-542500D02*
X-866367Y-542383D01*
X-866950Y-541917D01*
X-867450Y-541217D01*
X-867783Y-540400D01*
X-867950Y-539467D01*
Y-538533D01*
X-867783Y-537600D01*
X-867450Y-536783D01*
X-866950Y-536083D01*
X-866367Y-535617D01*
X-865700Y-535500D01*
X-865033Y-535617D01*
X-864450Y-536083D01*
X-863950Y-536783D01*
X-863617Y-537600D01*
X-863450Y-538533D01*
Y-539467D01*
X-863617Y-540400D01*
X-863950Y-541217D01*
X-864450Y-541917D01*
X-865033Y-542383D01*
X-865700Y-542500D01*
G01X-860567D02*
Y-535500D01*
X-858483D01*
X-857817Y-535850D01*
X-857400Y-536317D01*
X-857233Y-537250D01*
X-857400Y-538183D01*
X-857900Y-538767D01*
X-858483Y-539117D01*
X-860567D01*
G01X-858483D02*
X-857233Y-542500D01*
G01X-853767D02*
Y-535500D01*
X-851767D01*
X-851100Y-535850D01*
X-850600Y-536667D01*
X-850433Y-537600D01*
X-850600Y-538533D01*
X-851017Y-539233D01*
X-851767Y-539584D01*
X-853767D01*
G01X-845300Y-542500D02*
X-845967Y-542383D01*
X-846550Y-541917D01*
X-847050Y-541217D01*
X-847383Y-540400D01*
X-847550Y-539467D01*
Y-538533D01*
X-847383Y-537600D01*
X-847050Y-536783D01*
X-846550Y-536083D01*
X-845967Y-535617D01*
X-845300Y-535500D01*
X-844633Y-535617D01*
X-844050Y-536083D01*
X-843550Y-536783D01*
X-843217Y-537600D01*
X-843050Y-538533D01*
Y-539467D01*
X-843217Y-540400D01*
X-843550Y-541217D01*
X-844050Y-541917D01*
X-844633Y-542383D01*
X-845300Y-542500D01*
G01X-840167D02*
Y-535500D01*
X-838083D01*
X-837417Y-535850D01*
X-837000Y-536317D01*
X-836833Y-537250D01*
X-837000Y-538183D01*
X-837500Y-538767D01*
X-838083Y-539117D01*
X-840167D01*
G01X-838083D02*
X-836833Y-542500D01*
G01X-833783D02*
X-831700Y-535500D01*
X-829617Y-542500D01*
G01X-830367Y-540050D02*
X-833033D01*
G01X-824900Y-535500D02*
Y-542500D01*
G01X-826817Y-535500D02*
X-822983D01*
G01X-819100D02*
X-817100D01*
G01X-818100D02*
Y-542500D01*
G01X-819100D02*
X-817100D01*
G01X-811300D02*
X-811967Y-542383D01*
X-812550Y-541917D01*
X-813050Y-541217D01*
X-813383Y-540400D01*
X-813550Y-539467D01*
Y-538533D01*
X-813383Y-537600D01*
X-813050Y-536783D01*
X-812550Y-536083D01*
X-811967Y-535617D01*
X-811300Y-535500D01*
X-810633Y-535617D01*
X-810050Y-536083D01*
X-809550Y-536783D01*
X-809217Y-537600D01*
X-809050Y-538533D01*
Y-539467D01*
X-809217Y-540400D01*
X-809550Y-541217D01*
X-810050Y-541917D01*
X-810633Y-542383D01*
X-811300Y-542500D01*
G01X-806417D02*
Y-535500D01*
X-802583Y-542500D01*
Y-535500D01*
G01X-797700Y-542733D02*
X-797867Y-542617D01*
Y-542383D01*
X-797700Y-542267D01*
X-797533Y-542383D01*
Y-542617D01*
X-797700Y-542733D01*
G01X-784100Y-535500D02*
Y-542500D01*
G01X-786017Y-535500D02*
X-782183D01*
G01X-779050Y-542500D02*
Y-535500D01*
G01X-775550D02*
Y-542500D01*
G01Y-539000D02*
X-779050D01*
G01X-771500Y-535500D02*
X-769500D01*
G01X-770500D02*
Y-542500D01*
G01X-771500D02*
X-769500D01*
G01X-765450Y-541567D02*
X-764783Y-542150D01*
X-764033Y-542500D01*
X-763367D01*
X-762700Y-542150D01*
X-762200Y-541567D01*
X-761950Y-540750D01*
X-762117Y-539933D01*
X-762533Y-539233D01*
X-763283Y-538767D01*
X-764283Y-538533D01*
X-764867Y-538067D01*
X-765117Y-537250D01*
X-764950Y-536433D01*
X-764533Y-535850D01*
X-763950Y-535500D01*
X-763367D01*
X-762783Y-535733D01*
X-762283Y-536317D01*
G01X-751933Y-542500D02*
Y-535500D01*
X-750267D01*
X-749600Y-535850D01*
X-749100Y-536317D01*
X-748683Y-537017D01*
X-748350Y-537833D01*
X-748267Y-539000D01*
X-748350Y-540167D01*
X-748683Y-540983D01*
X-749100Y-541684D01*
X-749600Y-542150D01*
X-750267Y-542500D01*
X-751933D01*
G01X-744967D02*
Y-535500D01*
X-742883D01*
X-742217Y-535850D01*
X-741800Y-536317D01*
X-741633Y-537250D01*
X-741800Y-538183D01*
X-742300Y-538767D01*
X-742883Y-539117D01*
X-744967D01*
G01X-742883D02*
X-741633Y-542500D01*
G01X-738583D02*
X-736500Y-535500D01*
X-734417Y-542500D01*
G01X-735167Y-540050D02*
X-737833D01*
G01X-732200Y-535500D02*
X-731033Y-542500D01*
X-729700Y-535500D01*
X-728367Y-542500D01*
X-727200Y-535500D01*
G01X-723900D02*
X-721900D01*
G01X-722900D02*
Y-542500D01*
G01X-723900D02*
X-721900D01*
G01X-718017D02*
Y-535500D01*
X-714183Y-542500D01*
Y-535500D01*
G01X-708800Y-539000D02*
X-707133D01*
Y-541100D01*
X-707633Y-541800D01*
X-708217Y-542267D01*
X-709050Y-542500D01*
X-709883Y-542267D01*
X-710467Y-541800D01*
X-710967Y-541100D01*
X-711300Y-540283D01*
X-711467Y-539350D01*
Y-538533D01*
X-711300Y-537833D01*
X-710967Y-537017D01*
X-710467Y-536317D01*
X-709967Y-535850D01*
X-709300Y-535500D01*
X-708717D01*
X-708050Y-535733D01*
X-707550Y-536200D01*
G01X-696700Y-535500D02*
X-694700D01*
G01X-695700D02*
Y-542500D01*
G01X-696700D02*
X-694700D01*
G01X-690650Y-541567D02*
X-689983Y-542150D01*
X-689233Y-542500D01*
X-688567D01*
X-687900Y-542150D01*
X-687400Y-541567D01*
X-687150Y-540750D01*
X-687317Y-539933D01*
X-687733Y-539233D01*
X-688483Y-538767D01*
X-689483Y-538533D01*
X-690067Y-538067D01*
X-690317Y-537250D01*
X-690150Y-536433D01*
X-689733Y-535850D01*
X-689150Y-535500D01*
X-688567D01*
X-687983Y-535733D01*
X-687483Y-536317D01*
G01X-676967Y-542500D02*
Y-535500D01*
X-674883D01*
X-674217Y-535850D01*
X-673800Y-536317D01*
X-673633Y-537250D01*
X-673800Y-538183D01*
X-674300Y-538767D01*
X-674883Y-539117D01*
X-676967D01*
G01X-674883D02*
X-673633Y-542500D01*
G01X-666833D02*
X-670167D01*
Y-535500D01*
X-666833D01*
G01X-668167Y-538883D02*
X-670167D01*
G01X-659867Y-536083D02*
X-660367Y-535733D01*
X-660950Y-535500D01*
X-661617D01*
X-662367Y-535850D01*
X-662950Y-536433D01*
X-663367Y-537133D01*
X-663700Y-538300D01*
X-663783Y-539350D01*
X-663617Y-540400D01*
X-663367Y-541100D01*
X-662867Y-541800D01*
X-662283Y-542267D01*
X-661700Y-542500D01*
X-661117D01*
X-660533Y-542267D01*
X-660033Y-541917D01*
X-659617Y-541450D01*
G01X-653233Y-542500D02*
X-656567D01*
Y-535500D01*
X-653233D01*
G01X-654567Y-538883D02*
X-656567D01*
G01X-649100Y-535500D02*
X-647100D01*
G01X-648100D02*
Y-542500D01*
G01X-649100D02*
X-647100D01*
G01X-643383Y-535500D02*
X-641300Y-542500D01*
X-639217Y-535500D01*
G01X-632833Y-542500D02*
X-636167D01*
Y-535500D01*
X-632833D01*
G01X-634167Y-538883D02*
X-636167D01*
G01X-629533Y-542500D02*
Y-535500D01*
X-627867D01*
X-627200Y-535850D01*
X-626700Y-536317D01*
X-626283Y-537017D01*
X-625950Y-537833D01*
X-625867Y-539000D01*
X-625950Y-540167D01*
X-626283Y-540983D01*
X-626700Y-541684D01*
X-627200Y-542150D01*
X-627867Y-542500D01*
X-629533D01*
G01X-615100Y-535500D02*
X-613100D01*
G01X-614100D02*
Y-542500D01*
G01X-615100D02*
X-613100D01*
G01X-609217D02*
Y-535500D01*
X-605383Y-542500D01*
Y-535500D01*
G01X-872500Y-520500D02*
Y-527500D01*
G01X-874417Y-520500D02*
X-870583D01*
G01X-867450Y-527500D02*
Y-520500D01*
G01X-863950D02*
Y-527500D01*
G01Y-524000D02*
X-867450D01*
G01X-857233Y-527500D02*
X-860567D01*
Y-520500D01*
X-857233D01*
G01X-858567Y-523883D02*
X-860567D01*
G01X-846967Y-527500D02*
Y-520500D01*
X-844967D01*
X-844300Y-520850D01*
X-843800Y-521667D01*
X-843633Y-522600D01*
X-843800Y-523533D01*
X-844217Y-524233D01*
X-844967Y-524584D01*
X-846967D01*
G01X-840167Y-527500D02*
Y-520500D01*
X-838083D01*
X-837417Y-520850D01*
X-837000Y-521317D01*
X-836833Y-522250D01*
X-837000Y-523183D01*
X-837500Y-523767D01*
X-838083Y-524117D01*
X-840167D01*
G01X-838083D02*
X-836833Y-527500D01*
G01X-831700D02*
X-832367Y-527383D01*
X-832950Y-526917D01*
X-833450Y-526217D01*
X-833783Y-525400D01*
X-833950Y-524467D01*
Y-523533D01*
X-833783Y-522600D01*
X-833450Y-521783D01*
X-832950Y-521083D01*
X-832367Y-520617D01*
X-831700Y-520500D01*
X-831033Y-520617D01*
X-830450Y-521083D01*
X-829950Y-521783D01*
X-829617Y-522600D01*
X-829450Y-523533D01*
Y-524467D01*
X-829617Y-525400D01*
X-829950Y-526217D01*
X-830450Y-526917D01*
X-831033Y-527383D01*
X-831700Y-527500D01*
G01X-826567D02*
Y-520500D01*
X-824567D01*
X-823900Y-520850D01*
X-823400Y-521667D01*
X-823233Y-522600D01*
X-823400Y-523533D01*
X-823817Y-524233D01*
X-824567Y-524584D01*
X-826567D01*
G01X-819767Y-527500D02*
Y-520500D01*
X-817683D01*
X-817017Y-520850D01*
X-816600Y-521317D01*
X-816433Y-522250D01*
X-816600Y-523183D01*
X-817100Y-523767D01*
X-817683Y-524117D01*
X-819767D01*
G01X-817683D02*
X-816433Y-527500D01*
G01X-812300Y-520500D02*
X-810300D01*
G01X-811300D02*
Y-527500D01*
G01X-812300D02*
X-810300D01*
G01X-802833D02*
X-806167D01*
Y-520500D01*
X-802833D01*
G01X-804167Y-523883D02*
X-806167D01*
G01X-797700Y-520500D02*
Y-527500D01*
G01X-799617Y-520500D02*
X-795783D01*
G01X-792983Y-527500D02*
X-790900Y-520500D01*
X-788817Y-527500D01*
G01X-789567Y-525050D02*
X-792233D01*
G01X-785767Y-527500D02*
Y-520500D01*
X-783683D01*
X-783017Y-520850D01*
X-782600Y-521317D01*
X-782433Y-522250D01*
X-782600Y-523183D01*
X-783100Y-523767D01*
X-783683Y-524117D01*
X-785767D01*
G01X-783683D02*
X-782433Y-527500D01*
G01X-777300D02*
Y-524350D01*
X-778967Y-520500D01*
G01X-775633D02*
X-777300Y-524350D01*
G01X-765367Y-527500D02*
Y-520500D01*
X-763367D01*
X-762700Y-520850D01*
X-762200Y-521667D01*
X-762033Y-522600D01*
X-762200Y-523533D01*
X-762617Y-524233D01*
X-763367Y-524584D01*
X-765367D01*
G01X-758567Y-527500D02*
Y-520500D01*
X-756483D01*
X-755817Y-520850D01*
X-755400Y-521317D01*
X-755233Y-522250D01*
X-755400Y-523183D01*
X-755900Y-523767D01*
X-756483Y-524117D01*
X-758567D01*
G01X-756483D02*
X-755233Y-527500D01*
G01X-750100D02*
X-750767Y-527383D01*
X-751350Y-526917D01*
X-751850Y-526217D01*
X-752183Y-525400D01*
X-752350Y-524467D01*
Y-523533D01*
X-752183Y-522600D01*
X-751850Y-521783D01*
X-751350Y-521083D01*
X-750767Y-520617D01*
X-750100Y-520500D01*
X-749433Y-520617D01*
X-748850Y-521083D01*
X-748350Y-521783D01*
X-748017Y-522600D01*
X-747850Y-523533D01*
Y-524467D01*
X-748017Y-525400D01*
X-748350Y-526217D01*
X-748850Y-526917D01*
X-749433Y-527383D01*
X-750100Y-527500D01*
G01X-744967D02*
Y-520500D01*
X-742967D01*
X-742300Y-520850D01*
X-741800Y-521667D01*
X-741633Y-522600D01*
X-741800Y-523533D01*
X-742217Y-524233D01*
X-742967Y-524584D01*
X-744967D01*
G01X-734833Y-527500D02*
X-738167D01*
Y-520500D01*
X-734833D01*
G01X-736167Y-523883D02*
X-738167D01*
G01X-731367Y-527500D02*
Y-520500D01*
X-729283D01*
X-728617Y-520850D01*
X-728200Y-521317D01*
X-728033Y-522250D01*
X-728200Y-523183D01*
X-728700Y-523767D01*
X-729283Y-524117D01*
X-731367D01*
G01X-729283D02*
X-728033Y-527500D01*
G01X-722900Y-520500D02*
Y-527500D01*
G01X-724817Y-520500D02*
X-720983D01*
G01X-716100Y-527500D02*
Y-524350D01*
X-717767Y-520500D01*
G01X-714433D02*
X-716100Y-524350D01*
G01X-702500Y-527500D02*
X-703167Y-527383D01*
X-703750Y-526917D01*
X-704250Y-526217D01*
X-704583Y-525400D01*
X-704750Y-524467D01*
Y-523533D01*
X-704583Y-522600D01*
X-704250Y-521783D01*
X-703750Y-521083D01*
X-703167Y-520617D01*
X-702500Y-520500D01*
X-701833Y-520617D01*
X-701250Y-521083D01*
X-700750Y-521783D01*
X-700417Y-522600D01*
X-700250Y-523533D01*
Y-524467D01*
X-700417Y-525400D01*
X-700750Y-526217D01*
X-701250Y-526917D01*
X-701833Y-527383D01*
X-702500Y-527500D01*
G01X-697283D02*
Y-520500D01*
X-694117D01*
G01X-695283Y-523883D02*
X-697283D01*
G01X-684267Y-527500D02*
Y-520500D01*
X-682100Y-526333D01*
X-679933Y-520500D01*
Y-527500D01*
G01X-676300Y-520500D02*
X-674300D01*
G01X-675300D02*
Y-527500D01*
G01X-676300D02*
X-674300D01*
G01X-666667Y-521083D02*
X-667167Y-520733D01*
X-667750Y-520500D01*
X-668417D01*
X-669167Y-520850D01*
X-669750Y-521433D01*
X-670167Y-522133D01*
X-670500Y-523300D01*
X-670583Y-524350D01*
X-670417Y-525400D01*
X-670167Y-526100D01*
X-669667Y-526800D01*
X-669083Y-527267D01*
X-668500Y-527500D01*
X-667917D01*
X-667333Y-527267D01*
X-666833Y-526917D01*
X-666417Y-526450D01*
G01X-663367Y-527500D02*
Y-520500D01*
X-661283D01*
X-660617Y-520850D01*
X-660200Y-521317D01*
X-660033Y-522250D01*
X-660200Y-523183D01*
X-660700Y-523767D01*
X-661283Y-524117D01*
X-663367D01*
G01X-661283D02*
X-660033Y-527500D01*
G01X-654900D02*
X-655567Y-527383D01*
X-656150Y-526917D01*
X-656650Y-526217D01*
X-656983Y-525400D01*
X-657150Y-524467D01*
Y-523533D01*
X-656983Y-522600D01*
X-656650Y-521783D01*
X-656150Y-521083D01*
X-655567Y-520617D01*
X-654900Y-520500D01*
X-654233Y-520617D01*
X-653650Y-521083D01*
X-653150Y-521783D01*
X-652817Y-522600D01*
X-652650Y-523533D01*
Y-524467D01*
X-652817Y-525400D01*
X-653150Y-526217D01*
X-653650Y-526917D01*
X-654233Y-527383D01*
X-654900Y-527500D01*
G01X-649850Y-526567D02*
X-649183Y-527150D01*
X-648433Y-527500D01*
X-647767D01*
X-647100Y-527150D01*
X-646600Y-526567D01*
X-646350Y-525750D01*
X-646517Y-524933D01*
X-646933Y-524233D01*
X-647683Y-523767D01*
X-648683Y-523533D01*
X-649267Y-523067D01*
X-649517Y-522250D01*
X-649350Y-521433D01*
X-648933Y-520850D01*
X-648350Y-520500D01*
X-647767D01*
X-647183Y-520733D01*
X-646683Y-521317D01*
G01X-641300Y-527500D02*
X-641967Y-527383D01*
X-642550Y-526917D01*
X-643050Y-526217D01*
X-643383Y-525400D01*
X-643550Y-524467D01*
Y-523533D01*
X-643383Y-522600D01*
X-643050Y-521783D01*
X-642550Y-521083D01*
X-641967Y-520617D01*
X-641300Y-520500D01*
X-640633Y-520617D01*
X-640050Y-521083D01*
X-639550Y-521783D01*
X-639217Y-522600D01*
X-639050Y-523533D01*
Y-524467D01*
X-639217Y-525400D01*
X-639550Y-526217D01*
X-640050Y-526917D01*
X-640633Y-527383D01*
X-641300Y-527500D01*
G01X-636083D02*
Y-520500D01*
X-632917D01*
G01X-634083Y-523883D02*
X-636083D01*
G01X-627700Y-520500D02*
Y-527500D01*
G01X-629617Y-520500D02*
X-625783D01*
G01X-872500Y-505500D02*
Y-512500D01*
G01X-874417Y-505500D02*
X-870583D01*
G01X-867450Y-512500D02*
Y-505500D01*
G01X-863950D02*
Y-512500D01*
G01Y-509000D02*
X-867450D01*
G01X-859900Y-505500D02*
X-857900D01*
G01X-858900D02*
Y-512500D01*
G01X-859900D02*
X-857900D01*
G01X-853850Y-511567D02*
X-853183Y-512150D01*
X-852433Y-512500D01*
X-851767D01*
X-851100Y-512150D01*
X-850600Y-511567D01*
X-850350Y-510750D01*
X-850517Y-509933D01*
X-850933Y-509233D01*
X-851683Y-508767D01*
X-852683Y-508533D01*
X-853267Y-508067D01*
X-853517Y-507250D01*
X-853350Y-506433D01*
X-852933Y-505850D01*
X-852350Y-505500D01*
X-851767D01*
X-851183Y-505733D01*
X-850683Y-506317D01*
G01X-840333Y-512500D02*
Y-505500D01*
X-838667D01*
X-838000Y-505850D01*
X-837500Y-506317D01*
X-837083Y-507017D01*
X-836750Y-507833D01*
X-836667Y-509000D01*
X-836750Y-510167D01*
X-837083Y-510983D01*
X-837500Y-511684D01*
X-838000Y-512150D01*
X-838667Y-512500D01*
X-840333D01*
G01X-833367D02*
Y-505500D01*
X-831283D01*
X-830617Y-505850D01*
X-830200Y-506317D01*
X-830033Y-507250D01*
X-830200Y-508183D01*
X-830700Y-508767D01*
X-831283Y-509117D01*
X-833367D01*
G01X-831283D02*
X-830033Y-512500D01*
G01X-826983D02*
X-824900Y-505500D01*
X-822817Y-512500D01*
G01X-823567Y-510050D02*
X-826233D01*
G01X-820600Y-505500D02*
X-819433Y-512500D01*
X-818100Y-505500D01*
X-816767Y-512500D01*
X-815600Y-505500D01*
G01X-812300D02*
X-810300D01*
G01X-811300D02*
Y-512500D01*
G01X-812300D02*
X-810300D01*
G01X-806417D02*
Y-505500D01*
X-802583Y-512500D01*
Y-505500D01*
G01X-797200Y-509000D02*
X-795533D01*
Y-511100D01*
X-796033Y-511800D01*
X-796617Y-512267D01*
X-797450Y-512500D01*
X-798283Y-512267D01*
X-798867Y-511800D01*
X-799367Y-511100D01*
X-799700Y-510283D01*
X-799867Y-509350D01*
Y-508533D01*
X-799700Y-507833D01*
X-799367Y-507017D01*
X-798867Y-506317D01*
X-798367Y-505850D01*
X-797700Y-505500D01*
X-797117D01*
X-796450Y-505733D01*
X-795950Y-506200D01*
G01X-782267Y-506083D02*
X-782767Y-505733D01*
X-783350Y-505500D01*
X-784017D01*
X-784767Y-505850D01*
X-785350Y-506433D01*
X-785767Y-507133D01*
X-786100Y-508300D01*
X-786183Y-509350D01*
X-786017Y-510400D01*
X-785767Y-511100D01*
X-785267Y-511800D01*
X-784683Y-512267D01*
X-784100Y-512500D01*
X-783517D01*
X-782933Y-512267D01*
X-782433Y-511917D01*
X-782017Y-511450D01*
G01X-777300Y-512500D02*
X-777967Y-512383D01*
X-778550Y-511917D01*
X-779050Y-511217D01*
X-779383Y-510400D01*
X-779550Y-509467D01*
Y-508533D01*
X-779383Y-507600D01*
X-779050Y-506783D01*
X-778550Y-506083D01*
X-777967Y-505617D01*
X-777300Y-505500D01*
X-776633Y-505617D01*
X-776050Y-506083D01*
X-775550Y-506783D01*
X-775217Y-507600D01*
X-775050Y-508533D01*
Y-509467D01*
X-775217Y-510400D01*
X-775550Y-511217D01*
X-776050Y-511917D01*
X-776633Y-512383D01*
X-777300Y-512500D01*
G01X-772417D02*
Y-505500D01*
X-768583Y-512500D01*
Y-505500D01*
G01X-763700D02*
Y-512500D01*
G01X-765617Y-505500D02*
X-761783D01*
G01X-758983Y-512500D02*
X-756900Y-505500D01*
X-754817Y-512500D01*
G01X-755567Y-510050D02*
X-758233D01*
G01X-751100Y-505500D02*
X-749100D01*
G01X-750100D02*
Y-512500D01*
G01X-751100D02*
X-749100D01*
G01X-745217D02*
Y-505500D01*
X-741383Y-512500D01*
Y-505500D01*
G01X-738250Y-511567D02*
X-737583Y-512150D01*
X-736833Y-512500D01*
X-736167D01*
X-735500Y-512150D01*
X-735000Y-511567D01*
X-734750Y-510750D01*
X-734917Y-509933D01*
X-735333Y-509233D01*
X-736083Y-508767D01*
X-737083Y-508533D01*
X-737667Y-508067D01*
X-737917Y-507250D01*
X-737750Y-506433D01*
X-737333Y-505850D01*
X-736750Y-505500D01*
X-736167D01*
X-735583Y-505733D01*
X-735083Y-506317D01*
G01X-723900Y-505500D02*
X-721900D01*
G01X-722900D02*
Y-512500D01*
G01X-723900D02*
X-721900D01*
G01X-718017D02*
Y-505500D01*
X-714183Y-512500D01*
Y-505500D01*
G01X-710883Y-512500D02*
Y-505500D01*
X-707717D01*
G01X-708883Y-508883D02*
X-710883D01*
G01X-702500Y-512500D02*
X-703167Y-512383D01*
X-703750Y-511917D01*
X-704250Y-511217D01*
X-704583Y-510400D01*
X-704750Y-509467D01*
Y-508533D01*
X-704583Y-507600D01*
X-704250Y-506783D01*
X-703750Y-506083D01*
X-703167Y-505617D01*
X-702500Y-505500D01*
X-701833Y-505617D01*
X-701250Y-506083D01*
X-700750Y-506783D01*
X-700417Y-507600D01*
X-700250Y-508533D01*
Y-509467D01*
X-700417Y-510400D01*
X-700750Y-511217D01*
X-701250Y-511917D01*
X-701833Y-512383D01*
X-702500Y-512500D01*
G01X-697367D02*
Y-505500D01*
X-695283D01*
X-694617Y-505850D01*
X-694200Y-506317D01*
X-694033Y-507250D01*
X-694200Y-508183D01*
X-694700Y-508767D01*
X-695283Y-509117D01*
X-697367D01*
G01X-695283D02*
X-694033Y-512500D01*
G01X-691067D02*
Y-505500D01*
X-688900Y-511333D01*
X-686733Y-505500D01*
Y-512500D01*
G01X-684183D02*
X-682100Y-505500D01*
X-680017Y-512500D01*
G01X-680767Y-510050D02*
X-683433D01*
G01X-675300Y-505500D02*
Y-512500D01*
G01X-677217Y-505500D02*
X-673383D01*
G01X-669500D02*
X-667500D01*
G01X-668500D02*
Y-512500D01*
G01X-669500D02*
X-667500D01*
G01X-661700D02*
X-662367Y-512383D01*
X-662950Y-511917D01*
X-663450Y-511217D01*
X-663783Y-510400D01*
X-663950Y-509467D01*
Y-508533D01*
X-663783Y-507600D01*
X-663450Y-506783D01*
X-662950Y-506083D01*
X-662367Y-505617D01*
X-661700Y-505500D01*
X-661033Y-505617D01*
X-660450Y-506083D01*
X-659950Y-506783D01*
X-659617Y-507600D01*
X-659450Y-508533D01*
Y-509467D01*
X-659617Y-510400D01*
X-659950Y-511217D01*
X-660450Y-511917D01*
X-661033Y-512383D01*
X-661700Y-512500D01*
G01X-656817D02*
Y-505500D01*
X-652983Y-512500D01*
Y-505500D01*
G01X-643800D02*
X-642633Y-512500D01*
X-641300Y-505500D01*
X-639967Y-512500D01*
X-638800Y-505500D01*
G01X-636250Y-512500D02*
Y-505500D01*
G01X-632750D02*
Y-512500D01*
G01Y-509000D02*
X-636250D01*
G01X-628700Y-505500D02*
X-626700D01*
G01X-627700D02*
Y-512500D01*
G01X-628700D02*
X-626700D01*
G01X-619067Y-506083D02*
X-619567Y-505733D01*
X-620150Y-505500D01*
X-620817D01*
X-621567Y-505850D01*
X-622150Y-506433D01*
X-622567Y-507133D01*
X-622900Y-508300D01*
X-622983Y-509350D01*
X-622817Y-510400D01*
X-622567Y-511100D01*
X-622067Y-511800D01*
X-621483Y-512267D01*
X-620900Y-512500D01*
X-620317D01*
X-619733Y-512267D01*
X-619233Y-511917D01*
X-618817Y-511450D01*
G01X-615850Y-512500D02*
Y-505500D01*
G01X-612350D02*
Y-512500D01*
G01Y-509000D02*
X-615850D01*
G01X-601500Y-505500D02*
X-599500D01*
G01X-600500D02*
Y-512500D01*
G01X-601500D02*
X-599500D01*
G01X-595450Y-511567D02*
X-594783Y-512150D01*
X-594033Y-512500D01*
X-593367D01*
X-592700Y-512150D01*
X-592200Y-511567D01*
X-591950Y-510750D01*
X-592117Y-509933D01*
X-592533Y-509233D01*
X-593283Y-508767D01*
X-594283Y-508533D01*
X-594867Y-508067D01*
X-595117Y-507250D01*
X-594950Y-506433D01*
X-594533Y-505850D01*
X-593950Y-505500D01*
X-593367D01*
X-592783Y-505733D01*
X-592283Y-506317D01*
G01X-858133Y-452500D02*
Y-445500D01*
X-856467D01*
X-855800Y-445850D01*
X-855300Y-446317D01*
X-854883Y-447017D01*
X-854550Y-447833D01*
X-854467Y-449000D01*
X-854550Y-450167D01*
X-854883Y-450983D01*
X-855300Y-451684D01*
X-855800Y-452150D01*
X-856467Y-452500D01*
X-858133D01*
G01X-847833D02*
X-851167D01*
Y-445500D01*
X-847833D01*
G01X-849167Y-448883D02*
X-851167D01*
G01X-844450Y-451567D02*
X-843783Y-452150D01*
X-843033Y-452500D01*
X-842367D01*
X-841700Y-452150D01*
X-841200Y-451567D01*
X-840950Y-450750D01*
X-841117Y-449933D01*
X-841533Y-449233D01*
X-842283Y-448767D01*
X-843283Y-448533D01*
X-843867Y-448067D01*
X-844117Y-447250D01*
X-843950Y-446433D01*
X-843533Y-445850D01*
X-842950Y-445500D01*
X-842367D01*
X-841783Y-445733D01*
X-841283Y-446317D01*
G01X-836900Y-445500D02*
X-834900D01*
G01X-835900D02*
Y-452500D01*
G01X-836900D02*
X-834900D01*
G01X-828600Y-449000D02*
X-826933D01*
Y-451100D01*
X-827433Y-451800D01*
X-828017Y-452267D01*
X-828850Y-452500D01*
X-829683Y-452267D01*
X-830267Y-451800D01*
X-830767Y-451100D01*
X-831100Y-450283D01*
X-831267Y-449350D01*
Y-448533D01*
X-831100Y-447833D01*
X-830767Y-447017D01*
X-830267Y-446317D01*
X-829767Y-445850D01*
X-829100Y-445500D01*
X-828517D01*
X-827850Y-445733D01*
X-827350Y-446200D01*
G01X-824217Y-452500D02*
Y-445500D01*
X-820383Y-452500D01*
Y-445500D01*
G01X-813833Y-452500D02*
X-817167D01*
Y-445500D01*
X-813833D01*
G01X-815167Y-448883D02*
X-817167D01*
G01X-810367Y-452500D02*
Y-445500D01*
X-808283D01*
X-807617Y-445850D01*
X-807200Y-446317D01*
X-807033Y-447250D01*
X-807200Y-448183D01*
X-807700Y-448767D01*
X-808283Y-449117D01*
X-810367D01*
G01X-808283D02*
X-807033Y-452500D01*
G01X-858133D02*
Y-445500D01*
X-856467D01*
X-855800Y-445850D01*
X-855300Y-446317D01*
X-854883Y-447017D01*
X-854550Y-447833D01*
X-854467Y-449000D01*
X-854550Y-450167D01*
X-854883Y-450983D01*
X-855300Y-451684D01*
X-855800Y-452150D01*
X-856467Y-452500D01*
X-858133D01*
G01X-847833D02*
X-851167D01*
Y-445500D01*
X-847833D01*
G01X-849167Y-448883D02*
X-851167D01*
G01X-844450Y-451567D02*
X-843783Y-452150D01*
X-843033Y-452500D01*
X-842367D01*
X-841700Y-452150D01*
X-841200Y-451567D01*
X-840950Y-450750D01*
X-841117Y-449933D01*
X-841533Y-449233D01*
X-842283Y-448767D01*
X-843283Y-448533D01*
X-843867Y-448067D01*
X-844117Y-447250D01*
X-843950Y-446433D01*
X-843533Y-445850D01*
X-842950Y-445500D01*
X-842367D01*
X-841783Y-445733D01*
X-841283Y-446317D01*
G01X-836900Y-445500D02*
X-834900D01*
G01X-835900D02*
Y-452500D01*
G01X-836900D02*
X-834900D01*
G01X-828600Y-449000D02*
X-826933D01*
Y-451100D01*
X-827433Y-451800D01*
X-828017Y-452267D01*
X-828850Y-452500D01*
X-829683Y-452267D01*
X-830267Y-451800D01*
X-830767Y-451100D01*
X-831100Y-450283D01*
X-831267Y-449350D01*
Y-448533D01*
X-831100Y-447833D01*
X-830767Y-447017D01*
X-830267Y-446317D01*
X-829767Y-445850D01*
X-829100Y-445500D01*
X-828517D01*
X-827850Y-445733D01*
X-827350Y-446200D01*
G01X-824217Y-452500D02*
Y-445500D01*
X-820383Y-452500D01*
Y-445500D01*
G01X-813833Y-452500D02*
X-817167D01*
Y-445500D01*
X-813833D01*
G01X-815167Y-448883D02*
X-817167D01*
G01X-810367Y-452500D02*
Y-445500D01*
X-808283D01*
X-807617Y-445850D01*
X-807200Y-446317D01*
X-807033Y-447250D01*
X-807200Y-448183D01*
X-807700Y-448767D01*
X-808283Y-449117D01*
X-810367D01*
G01X-808283D02*
X-807033Y-452500D01*
G01X-642033Y-455000D02*
Y-448000D01*
X-640367D01*
X-639700Y-448350D01*
X-639200Y-448817D01*
X-638783Y-449517D01*
X-638450Y-450333D01*
X-638367Y-451500D01*
X-638450Y-452667D01*
X-638783Y-453483D01*
X-639200Y-454184D01*
X-639700Y-454650D01*
X-640367Y-455000D01*
X-642033D01*
G01X-635483D02*
X-633400Y-448000D01*
X-631317Y-455000D01*
G01X-632067Y-452550D02*
X-634733D01*
G01X-626600Y-448000D02*
Y-455000D01*
G01X-628517Y-448000D02*
X-624683D01*
G01X-618133Y-455000D02*
X-621467D01*
Y-448000D01*
X-618133D01*
G01X-619467Y-451383D02*
X-621467D01*
M02*
